(kicad_sch
	(version 20231120)
	(generator "eeschema")
	(generator_version "8.0")
	(paper "A3")
	(title_block
		(title "Jetson Orin Baseboard")
		(date "2025-03-12")
		(rev "1.3.4")
		(company "Antmicro Ltd")
		(comment 1 "www.antmicro.com")
	)
	(junction
		(at 294.64 170.18)
		(diameter 0)
		(color 0 0 0 0)
	)
	(junction
		(at 298.45 184.15)
		(diameter 0)
		(color 0 0 0 0)
	)
	(junction
		(at 384.81 177.8)
		(diameter 0)
		(color 0 0 0 0)
	)
	(junction
		(at 30.48 165.1)
		(diameter 0)
		(color 0 0 0 0)
	)
	(junction
		(at 46.99 156.21)
		(diameter 0)
		(color 0 0 0 0)
	)
	(junction
		(at 186.69 194.31)
		(diameter 0)
		(color 0 0 0 0)
	)
	(junction
		(at 269.24 215.9)
		(diameter 0)
		(color 0 0 0 0)
	)
	(junction
		(at 86.36 78.74)
		(diameter 0)
		(color 0 0 0 0)
	)
	(junction
		(at 66.04 165.1)
		(diameter 0)
		(color 0 0 0 0)
	)
	(junction
		(at 384.81 180.34)
		(diameter 0)
		(color 0 0 0 0)
	)
	(junction
		(at 154.94 160.02)
		(diameter 0)
		(color 0 0 0 0)
	)
	(junction
		(at 246.38 181.61)
		(diameter 0)
		(color 0 0 0 0)
	)
	(junction
		(at 179.07 194.31)
		(diameter 0)
		(color 0 0 0 0)
	)
	(junction
		(at 171.45 194.31)
		(diameter 0)
		(color 0 0 0 0)
	)
	(junction
		(at 163.83 194.31)
		(diameter 0)
		(color 0 0 0 0)
	)
	(junction
		(at 179.07 147.32)
		(diameter 0)
		(color 0 0 0 0)
	)
	(junction
		(at 154.94 194.31)
		(diameter 0)
		(color 0 0 0 0)
	)
	(junction
		(at 228.6 215.9)
		(diameter 0)
		(color 0 0 0 0)
	)
	(junction
		(at 248.92 184.15)
		(diameter 0)
		(color 0 0 0 0)
	)
	(junction
		(at 194.31 194.31)
		(diameter 0)
		(color 0 0 0 0)
	)
	(junction
		(at 76.2 78.74)
		(diameter 0)
		(color 0 0 0 0)
	)
	(junction
		(at 194.31 139.7)
		(diameter 0)
		(color 0 0 0 0)
	)
	(junction
		(at 265.43 186.69)
		(diameter 0)
		(color 0 0 0 0)
	)
	(junction
		(at 339.09 187.96)
		(diameter 0)
		(color 0 0 0 0)
	)
	(junction
		(at 76.2 189.23)
		(diameter 0)
		(color 0 0 0 0)
	)
	(junction
		(at 256.54 172.72)
		(diameter 0)
		(color 0 0 0 0)
	)
	(junction
		(at 146.05 162.56)
		(diameter 0)
		(color 0 0 0 0)
	)
	(junction
		(at 46.99 165.1)
		(diameter 0)
		(color 0 0 0 0)
	)
	(junction
		(at 163.83 154.94)
		(diameter 0)
		(color 0 0 0 0)
	)
	(junction
		(at 182.88 194.31)
		(diameter 0)
		(color 0 0 0 0)
	)
	(junction
		(at 201.93 137.16)
		(diameter 0)
		(color 0 0 0 0)
	)
	(junction
		(at 308.61 224.79)
		(diameter 0)
		(color 0 0 0 0)
	)
	(junction
		(at 384.81 185.42)
		(diameter 0)
		(color 0 0 0 0)
	)
	(junction
		(at 294.64 181.61)
		(diameter 0)
		(color 0 0 0 0)
	)
	(junction
		(at 260.35 191.77)
		(diameter 0)
		(color 0 0 0 0)
	)
	(junction
		(at 347.98 187.96)
		(diameter 0)
		(color 0 0 0 0)
	)
	(junction
		(at 384.81 182.88)
		(diameter 0)
		(color 0 0 0 0)
	)
	(junction
		(at 256.54 181.61)
		(diameter 0)
		(color 0 0 0 0)
	)
	(junction
		(at 186.69 144.78)
		(diameter 0)
		(color 0 0 0 0)
	)
	(junction
		(at 292.1 191.77)
		(diameter 0)
		(color 0 0 0 0)
	)
	(junction
		(at 93.98 168.91)
		(diameter 0)
		(color 0 0 0 0)
	)
	(junction
		(at 260.35 184.15)
		(diameter 0)
		(color 0 0 0 0)
	)
	(junction
		(at 171.45 152.4)
		(diameter 0)
		(color 0 0 0 0)
	)
	(junction
		(at 384.81 187.96)
		(diameter 0)
		(color 0 0 0 0)
	)
	(no_connect
		(at 99.06 154.94)
	)
	(no_connect
		(at 358.14 182.88)
	)
	(no_connect
		(at 124.46 127)
	)
	(no_connect
		(at 124.46 175.26)
	)
	(wire
		(pts
			(xy 76.2 77.47) (xy 76.2 78.74)
		)
		(stroke
			(width 0)
			(type default)
		)
	)
	(wire
		(pts
			(xy 186.69 144.78) (xy 214.63 144.78)
		)
		(stroke
			(width 0)
			(type default)
		)
	)
	(wire
		(pts
			(xy 269.24 143.51) (xy 271.78 143.51)
		)
		(stroke
			(width 0)
			(type default)
		)
	)
	(wire
		(pts
			(xy 384.81 180.34) (xy 384.81 182.88)
		)
		(stroke
			(width 0)
			(type default)
		)
	)
	(wire
		(pts
			(xy 295.91 48.26) (xy 314.96 48.26)
		)
		(stroke
			(width 0)
			(type default)
		)
	)
	(wire
		(pts
			(xy 243.84 184.15) (xy 248.92 184.15)
		)
		(stroke
			(width 0)
			(type default)
		)
	)
	(wire
		(pts
			(xy 269.24 215.9) (xy 295.91 215.9)
		)
		(stroke
			(width 0)
			(type default)
		)
	)
	(wire
		(pts
			(xy 344.17 175.26) (xy 358.14 175.26)
		)
		(stroke
			(width 0)
			(type default)
		)
	)
	(wire
		(pts
			(xy 124.46 99.06) (xy 165.1 99.06)
		)
		(stroke
			(width 0)
			(type default)
		)
	)
	(wire
		(pts
			(xy 66.04 154.94) (xy 66.04 157.48)
		)
		(stroke
			(width 0)
			(type default)
		)
	)
	(wire
		(pts
			(xy 300.99 215.9) (xy 308.61 215.9)
		)
		(stroke
			(width 0)
			(type default)
		)
	)
	(wire
		(pts
			(xy 146.05 190.5) (xy 146.05 194.31)
		)
		(stroke
			(width 0)
			(type default)
		)
	)
	(wire
		(pts
			(xy 284.48 140.97) (xy 284.48 139.7)
		)
		(stroke
			(width 0)
			(type default)
		)
	)
	(wire
		(pts
			(xy 246.38 181.61) (xy 256.54 181.61)
		)
		(stroke
			(width 0)
			(type default)
		)
	)
	(wire
		(pts
			(xy 74.93 121.92) (xy 99.06 121.92)
		)
		(stroke
			(width 0)
			(type default)
		)
	)
	(wire
		(pts
			(xy 76.2 78.74) (xy 86.36 78.74)
		)
		(stroke
			(width 0)
			(type default)
		)
	)
	(wire
		(pts
			(xy 294.64 170.18) (xy 298.45 170.18)
		)
		(stroke
			(width 0)
			(type default)
		)
	)
	(wire
		(pts
			(xy 124.46 91.44) (xy 165.1 91.44)
		)
		(stroke
			(width 0)
			(type default)
		)
	)
	(wire
		(pts
			(xy 383.54 187.96) (xy 384.81 187.96)
		)
		(stroke
			(width 0)
			(type default)
		)
	)
	(wire
		(pts
			(xy 287.02 184.15) (xy 298.45 184.15)
		)
		(stroke
			(width 0)
			(type default)
		)
	)
	(wire
		(pts
			(xy 283.21 147.32) (xy 358.14 147.32)
		)
		(stroke
			(width 0)
			(type default)
		)
	)
	(wire
		(pts
			(xy 54.61 156.21) (xy 54.61 158.75)
		)
		(stroke
			(width 0)
			(type default)
		)
	)
	(wire
		(pts
			(xy 281.94 140.97) (xy 284.48 140.97)
		)
		(stroke
			(width 0)
			(type default)
		)
	)
	(wire
		(pts
			(xy 74.93 129.54) (xy 99.06 129.54)
		)
		(stroke
			(width 0)
			(type default)
		)
	)
	(wire
		(pts
			(xy 281.94 153.67) (xy 283.21 153.67)
		)
		(stroke
			(width 0)
			(type default)
		)
	)
	(wire
		(pts
			(xy 284.48 143.51) (xy 284.48 144.78)
		)
		(stroke
			(width 0)
			(type default)
		)
	)
	(wire
		(pts
			(xy 295.91 96.52) (xy 314.96 96.52)
		)
		(stroke
			(width 0)
			(type default)
		)
	)
	(wire
		(pts
			(xy 217.17 162.56) (xy 270.51 162.56)
		)
		(stroke
			(width 0)
			(type default)
		)
	)
	(wire
		(pts
			(xy 46.99 154.94) (xy 46.99 156.21)
		)
		(stroke
			(width 0)
			(type default)
		)
	)
	(wire
		(pts
			(xy 339.09 187.96) (xy 347.98 187.96)
		)
		(stroke
			(width 0)
			(type default)
		)
	)
	(wire
		(pts
			(xy 287.02 179.07) (xy 292.1 179.07)
		)
		(stroke
			(width 0)
			(type default)
		)
	)
	(wire
		(pts
			(xy 71.12 111.76) (xy 99.06 111.76)
		)
		(stroke
			(width 0)
			(type default)
		)
	)
	(wire
		(pts
			(xy 76.2 186.69) (xy 76.2 189.23)
		)
		(stroke
			(width 0)
			(type default)
		)
	)
	(wire
		(pts
			(xy 295.91 93.98) (xy 314.96 93.98)
		)
		(stroke
			(width 0)
			(type default)
		)
	)
	(wire
		(pts
			(xy 69.85 168.91) (xy 83.82 168.91)
		)
		(stroke
			(width 0)
			(type default)
		)
	)
	(wire
		(pts
			(xy 256.54 181.61) (xy 266.7 181.61)
		)
		(stroke
			(width 0)
			(type default)
		)
	)
	(wire
		(pts
			(xy 124.46 104.14) (xy 165.1 104.14)
		)
		(stroke
			(width 0)
			(type default)
		)
	)
	(wire
		(pts
			(xy 256.54 172.72) (xy 260.35 172.72)
		)
		(stroke
			(width 0)
			(type default)
		)
	)
	(wire
		(pts
			(xy 124.46 119.38) (xy 147.32 119.38)
		)
		(stroke
			(width 0)
			(type default)
		)
	)
	(wire
		(pts
			(xy 46.99 162.56) (xy 46.99 165.1)
		)
		(stroke
			(width 0)
			(type default)
		)
	)
	(wire
		(pts
			(xy 124.46 88.9) (xy 165.1 88.9)
		)
		(stroke
			(width 0)
			(type default)
		)
	)
	(wire
		(pts
			(xy 383.54 175.26) (xy 384.81 175.26)
		)
		(stroke
			(width 0)
			(type default)
		)
	)
	(wire
		(pts
			(xy 269.24 215.9) (xy 269.24 217.17)
		)
		(stroke
			(width 0)
			(type default)
		)
	)
	(wire
		(pts
			(xy 308.61 170.18) (xy 308.61 181.61)
		)
		(stroke
			(width 0)
			(type default)
		)
	)
	(wire
		(pts
			(xy 243.84 181.61) (xy 246.38 181.61)
		)
		(stroke
			(width 0)
			(type default)
		)
	)
	(wire
		(pts
			(xy 283.21 137.16) (xy 358.14 137.16)
		)
		(stroke
			(width 0)
			(type default)
		)
	)
	(wire
		(pts
			(xy 71.12 137.16) (xy 99.06 137.16)
		)
		(stroke
			(width 0)
			(type default)
		)
	)
	(wire
		(pts
			(xy 124.46 144.78) (xy 186.69 144.78)
		)
		(stroke
			(width 0)
			(type default)
		)
	)
	(wire
		(pts
			(xy 306.07 167.64) (xy 358.14 167.64)
		)
		(stroke
			(width 0)
			(type default)
		)
	)
	(wire
		(pts
			(xy 284.48 144.78) (xy 358.14 144.78)
		)
		(stroke
			(width 0)
			(type default)
		)
	)
	(wire
		(pts
			(xy 146.05 194.31) (xy 154.94 194.31)
		)
		(stroke
			(width 0)
			(type default)
		)
	)
	(wire
		(pts
			(xy 124.46 106.68) (xy 165.1 106.68)
		)
		(stroke
			(width 0)
			(type default)
		)
	)
	(wire
		(pts
			(xy 270.51 137.16) (xy 270.51 138.43)
		)
		(stroke
			(width 0)
			(type default)
		)
	)
	(wire
		(pts
			(xy 30.48 165.1) (xy 30.48 167.64)
		)
		(stroke
			(width 0)
			(type default)
		)
	)
	(wire
		(pts
			(xy 294.64 181.61) (xy 308.61 181.61)
		)
		(stroke
			(width 0)
			(type default)
		)
	)
	(wire
		(pts
			(xy 163.83 194.31) (xy 171.45 194.31)
		)
		(stroke
			(width 0)
			(type default)
		)
	)
	(wire
		(pts
			(xy 384.81 185.42) (xy 384.81 187.96)
		)
		(stroke
			(width 0)
			(type default)
		)
	)
	(wire
		(pts
			(xy 383.54 180.34) (xy 384.81 180.34)
		)
		(stroke
			(width 0)
			(type default)
		)
	)
	(wire
		(pts
			(xy 260.35 172.72) (xy 260.35 173.99)
		)
		(stroke
			(width 0)
			(type default)
		)
	)
	(wire
		(pts
			(xy 74.93 114.3) (xy 99.06 114.3)
		)
		(stroke
			(width 0)
			(type default)
		)
	)
	(wire
		(pts
			(xy 217.17 160.02) (xy 269.24 160.02)
		)
		(stroke
			(width 0)
			(type default)
		)
	)
	(wire
		(pts
			(xy 265.43 186.69) (xy 265.43 191.77)
		)
		(stroke
			(width 0)
			(type default)
		)
	)
	(wire
		(pts
			(xy 54.61 111.76) (xy 66.04 111.76)
		)
		(stroke
			(width 0)
			(type default)
		)
	)
	(wire
		(pts
			(xy 171.45 207.01) (xy 176.53 207.01)
		)
		(stroke
			(width 0)
			(type default)
		)
	)
	(wire
		(pts
			(xy 66.04 165.1) (xy 74.93 165.1)
		)
		(stroke
			(width 0)
			(type default)
		)
	)
	(wire
		(pts
			(xy 298.45 170.18) (xy 298.45 171.45)
		)
		(stroke
			(width 0)
			(type default)
		)
	)
	(wire
		(pts
			(xy 270.51 161.29) (xy 271.78 161.29)
		)
		(stroke
			(width 0)
			(type default)
		)
	)
	(wire
		(pts
			(xy 248.92 184.15) (xy 260.35 184.15)
		)
		(stroke
			(width 0)
			(type default)
		)
	)
	(wire
		(pts
			(xy 271.78 158.75) (xy 269.24 158.75)
		)
		(stroke
			(width 0)
			(type default)
		)
	)
	(wire
		(pts
			(xy 308.61 170.18) (xy 358.14 170.18)
		)
		(stroke
			(width 0)
			(type default)
		)
	)
	(wire
		(pts
			(xy 163.83 190.5) (xy 163.83 194.31)
		)
		(stroke
			(width 0)
			(type default)
		)
	)
	(wire
		(pts
			(xy 124.46 160.02) (xy 154.94 160.02)
		)
		(stroke
			(width 0)
			(type default)
		)
	)
	(wire
		(pts
			(xy 306.07 167.64) (xy 306.07 184.15)
		)
		(stroke
			(width 0)
			(type default)
		)
	)
	(wire
		(pts
			(xy 97.79 177.8) (xy 97.79 179.07)
		)
		(stroke
			(width 0)
			(type default)
		)
	)
	(wire
		(pts
			(xy 269.24 140.97) (xy 269.24 139.7)
		)
		(stroke
			(width 0)
			(type default)
		)
	)
	(wire
		(pts
			(xy 217.17 139.7) (xy 269.24 139.7)
		)
		(stroke
			(width 0)
			(type default)
		)
	)
	(wire
		(pts
			(xy 313.69 186.69) (xy 313.69 187.96)
		)
		(stroke
			(width 0)
			(type default)
		)
	)
	(wire
		(pts
			(xy 228.6 215.9) (xy 269.24 215.9)
		)
		(stroke
			(width 0)
			(type default)
		)
	)
	(wire
		(pts
			(xy 87.63 165.1) (xy 87.63 166.37)
		)
		(stroke
			(width 0)
			(type default)
		)
	)
	(wire
		(pts
			(xy 347.98 187.96) (xy 347.98 190.5)
		)
		(stroke
			(width 0)
			(type default)
		)
	)
	(wire
		(pts
			(xy 313.69 77.47) (xy 313.69 78.74)
		)
		(stroke
			(width 0)
			(type default)
		)
	)
	(wire
		(pts
			(xy 124.46 139.7) (xy 194.31 139.7)
		)
		(stroke
			(width 0)
			(type default)
		)
	)
	(wire
		(pts
			(xy 260.35 179.07) (xy 260.35 184.15)
		)
		(stroke
			(width 0)
			(type default)
		)
	)
	(wire
		(pts
			(xy 298.45 176.53) (xy 298.45 184.15)
		)
		(stroke
			(width 0)
			(type default)
		)
	)
	(wire
		(pts
			(xy 308.61 226.06) (xy 308.61 224.79)
		)
		(stroke
			(width 0)
			(type default)
		)
	)
	(wire
		(pts
			(xy 260.35 191.77) (xy 265.43 191.77)
		)
		(stroke
			(width 0)
			(type default)
		)
	)
	(wire
		(pts
			(xy 186.69 194.31) (xy 194.31 194.31)
		)
		(stroke
			(width 0)
			(type default)
		)
	)
	(wire
		(pts
			(xy 285.75 170.18) (xy 294.64 170.18)
		)
		(stroke
			(width 0)
			(type default)
		)
	)
	(wire
		(pts
			(xy 283.21 146.05) (xy 283.21 147.32)
		)
		(stroke
			(width 0)
			(type default)
		)
	)
	(wire
		(pts
			(xy 182.88 194.31) (xy 182.88 199.39)
		)
		(stroke
			(width 0)
			(type default)
		)
	)
	(wire
		(pts
			(xy 281.94 146.05) (xy 283.21 146.05)
		)
		(stroke
			(width 0)
			(type default)
		)
	)
	(wire
		(pts
			(xy 194.31 139.7) (xy 214.63 139.7)
		)
		(stroke
			(width 0)
			(type default)
		)
	)
	(wire
		(pts
			(xy 283.21 152.4) (xy 358.14 152.4)
		)
		(stroke
			(width 0)
			(type default)
		)
	)
	(wire
		(pts
			(xy 270.51 162.56) (xy 270.51 161.29)
		)
		(stroke
			(width 0)
			(type default)
		)
	)
	(wire
		(pts
			(xy 76.2 189.23) (xy 93.98 189.23)
		)
		(stroke
			(width 0)
			(type default)
		)
	)
	(wire
		(pts
			(xy 283.21 138.43) (xy 281.94 138.43)
		)
		(stroke
			(width 0)
			(type default)
		)
	)
	(wire
		(pts
			(xy 124.46 177.8) (xy 228.6 177.8)
		)
		(stroke
			(width 0)
			(type default)
		)
	)
	(wire
		(pts
			(xy 124.46 147.32) (xy 179.07 147.32)
		)
		(stroke
			(width 0)
			(type default)
		)
	)
	(wire
		(pts
			(xy 76.2 201.93) (xy 76.2 200.66)
		)
		(stroke
			(width 0)
			(type default)
		)
	)
	(wire
		(pts
			(xy 265.43 186.69) (xy 266.7 186.69)
		)
		(stroke
			(width 0)
			(type default)
		)
	)
	(wire
		(pts
			(xy 271.78 156.21) (xy 269.24 156.21)
		)
		(stroke
			(width 0)
			(type default)
		)
	)
	(wire
		(pts
			(xy 270.51 153.67) (xy 270.51 152.4)
		)
		(stroke
			(width 0)
			(type default)
		)
	)
	(wire
		(pts
			(xy 194.31 139.7) (xy 194.31 185.42)
		)
		(stroke
			(width 0)
			(type default)
		)
	)
	(wire
		(pts
			(xy 295.91 91.44) (xy 314.96 91.44)
		)
		(stroke
			(width 0)
			(type default)
		)
	)
	(wire
		(pts
			(xy 54.61 119.38) (xy 66.04 119.38)
		)
		(stroke
			(width 0)
			(type default)
		)
	)
	(wire
		(pts
			(xy 171.45 185.42) (xy 171.45 194.31)
		)
		(stroke
			(width 0)
			(type default)
		)
	)
	(wire
		(pts
			(xy 54.61 147.32) (xy 99.06 147.32)
		)
		(stroke
			(width 0)
			(type default)
		)
	)
	(wire
		(pts
			(xy 97.79 88.9) (xy 99.06 88.9)
		)
		(stroke
			(width 0)
			(type default)
		)
	)
	(wire
		(pts
			(xy 270.51 138.43) (xy 271.78 138.43)
		)
		(stroke
			(width 0)
			(type default)
		)
	)
	(wire
		(pts
			(xy 163.83 154.94) (xy 214.63 154.94)
		)
		(stroke
			(width 0)
			(type default)
		)
	)
	(wire
		(pts
			(xy 217.17 144.78) (xy 269.24 144.78)
		)
		(stroke
			(width 0)
			(type default)
		)
	)
	(wire
		(pts
			(xy 217.17 166.37) (xy 248.92 166.37)
		)
		(stroke
			(width 0)
			(type default)
		)
	)
	(wire
		(pts
			(xy 266.7 179.07) (xy 265.43 179.07)
		)
		(stroke
			(width 0)
			(type default)
		)
	)
	(wire
		(pts
			(xy 294.64 176.53) (xy 294.64 181.61)
		)
		(stroke
			(width 0)
			(type default)
		)
	)
	(wire
		(pts
			(xy 287.02 186.69) (xy 288.29 186.69)
		)
		(stroke
			(width 0)
			(type default)
		)
	)
	(wire
		(pts
			(xy 260.35 190.5) (xy 260.35 191.77)
		)
		(stroke
			(width 0)
			(type default)
		)
	)
	(wire
		(pts
			(xy 74.93 152.4) (xy 99.06 152.4)
		)
		(stroke
			(width 0)
			(type default)
		)
	)
	(wire
		(pts
			(xy 156.21 121.92) (xy 165.1 121.92)
		)
		(stroke
			(width 0)
			(type default)
		)
	)
	(wire
		(pts
			(xy 76.2 78.74) (xy 76.2 81.28)
		)
		(stroke
			(width 0)
			(type default)
		)
	)
	(wire
		(pts
			(xy 292.1 198.12) (xy 292.1 199.39)
		)
		(stroke
			(width 0)
			(type default)
		)
	)
	(wire
		(pts
			(xy 383.54 177.8) (xy 384.81 177.8)
		)
		(stroke
			(width 0)
			(type default)
		)
	)
	(wire
		(pts
			(xy 76.2 181.61) (xy 76.2 180.34)
		)
		(stroke
			(width 0)
			(type default)
		)
	)
	(wire
		(pts
			(xy 124.46 166.37) (xy 212.09 166.37)
		)
		(stroke
			(width 0)
			(type default)
		)
	)
	(wire
		(pts
			(xy 308.61 231.14) (xy 308.61 232.41)
		)
		(stroke
			(width 0)
			(type default)
		)
	)
	(wire
		(pts
			(xy 30.48 165.1) (xy 35.56 165.1)
		)
		(stroke
			(width 0)
			(type default)
		)
	)
	(wire
		(pts
			(xy 124.46 114.3) (xy 165.1 114.3)
		)
		(stroke
			(width 0)
			(type default)
		)
	)
	(wire
		(pts
			(xy 384.81 177.8) (xy 384.81 180.34)
		)
		(stroke
			(width 0)
			(type default)
		)
	)
	(wire
		(pts
			(xy 60.96 198.12) (xy 69.85 198.12)
		)
		(stroke
			(width 0)
			(type default)
		)
	)
	(wire
		(pts
			(xy 71.12 127) (xy 99.06 127)
		)
		(stroke
			(width 0)
			(type default)
		)
	)
	(wire
		(pts
			(xy 124.46 111.76) (xy 165.1 111.76)
		)
		(stroke
			(width 0)
			(type default)
		)
	)
	(wire
		(pts
			(xy 201.93 185.42) (xy 201.93 194.31)
		)
		(stroke
			(width 0)
			(type default)
		)
	)
	(wire
		(pts
			(xy 300.99 224.79) (xy 308.61 224.79)
		)
		(stroke
			(width 0)
			(type default)
		)
	)
	(wire
		(pts
			(xy 71.12 119.38) (xy 99.06 119.38)
		)
		(stroke
			(width 0)
			(type default)
		)
	)
	(wire
		(pts
			(xy 46.99 156.21) (xy 54.61 156.21)
		)
		(stroke
			(width 0)
			(type default)
		)
	)
	(wire
		(pts
			(xy 288.29 186.69) (xy 288.29 187.96)
		)
		(stroke
			(width 0)
			(type default)
		)
	)
	(wire
		(pts
			(xy 295.91 74.93) (xy 314.96 74.93)
		)
		(stroke
			(width 0)
			(type default)
		)
	)
	(wire
		(pts
			(xy 313.69 101.6) (xy 313.69 102.87)
		)
		(stroke
			(width 0)
			(type default)
		)
	)
	(wire
		(pts
			(xy 295.91 67.31) (xy 314.96 67.31)
		)
		(stroke
			(width 0)
			(type default)
		)
	)
	(wire
		(pts
			(xy 171.45 203.2) (xy 171.45 207.01)
		)
		(stroke
			(width 0)
			(type default)
		)
	)
	(wire
		(pts
			(xy 384.81 187.96) (xy 384.81 189.23)
		)
		(stroke
			(width 0)
			(type default)
		)
	)
	(wire
		(pts
			(xy 228.6 215.9) (xy 228.6 177.8)
		)
		(stroke
			(width 0)
			(type default)
		)
	)
	(wire
		(pts
			(xy 295.91 99.06) (xy 314.96 99.06)
		)
		(stroke
			(width 0)
			(type default)
		)
	)
	(wire
		(pts
			(xy 154.94 185.42) (xy 154.94 194.31)
		)
		(stroke
			(width 0)
			(type default)
		)
	)
	(wire
		(pts
			(xy 87.63 160.02) (xy 87.63 158.75)
		)
		(stroke
			(width 0)
			(type default)
		)
	)
	(wire
		(pts
			(xy 269.24 213.36) (xy 269.24 215.9)
		)
		(stroke
			(width 0)
			(type default)
		)
	)
	(wire
		(pts
			(xy 46.99 165.1) (xy 52.07 165.1)
		)
		(stroke
			(width 0)
			(type default)
		)
	)
	(wire
		(pts
			(xy 86.36 86.36) (xy 86.36 91.44)
		)
		(stroke
			(width 0)
			(type default)
		)
	)
	(wire
		(pts
			(xy 314.96 77.47) (xy 313.69 77.47)
		)
		(stroke
			(width 0)
			(type default)
		)
	)
	(wire
		(pts
			(xy 383.54 185.42) (xy 384.81 185.42)
		)
		(stroke
			(width 0)
			(type default)
		)
	)
	(wire
		(pts
			(xy 270.51 146.05) (xy 270.51 147.32)
		)
		(stroke
			(width 0)
			(type default)
		)
	)
	(wire
		(pts
			(xy 339.09 186.69) (xy 339.09 187.96)
		)
		(stroke
			(width 0)
			(type default)
		)
	)
	(wire
		(pts
			(xy 99.06 177.8) (xy 97.79 177.8)
		)
		(stroke
			(width 0)
			(type default)
		)
	)
	(wire
		(pts
			(xy 313.69 53.34) (xy 313.69 54.61)
		)
		(stroke
			(width 0)
			(type default)
		)
	)
	(wire
		(pts
			(xy 308.61 215.9) (xy 308.61 224.79)
		)
		(stroke
			(width 0)
			(type default)
		)
	)
	(wire
		(pts
			(xy 54.61 121.92) (xy 69.85 121.92)
		)
		(stroke
			(width 0)
			(type default)
		)
	)
	(wire
		(pts
			(xy 320.04 187.96) (xy 323.85 187.96)
		)
		(stroke
			(width 0)
			(type default)
		)
	)
	(wire
		(pts
			(xy 76.2 189.23) (xy 76.2 190.5)
		)
		(stroke
			(width 0)
			(type default)
		)
	)
	(wire
		(pts
			(xy 54.61 129.54) (xy 69.85 129.54)
		)
		(stroke
			(width 0)
			(type default)
		)
	)
	(wire
		(pts
			(xy 217.17 152.4) (xy 270.51 152.4)
		)
		(stroke
			(width 0)
			(type default)
		)
	)
	(wire
		(pts
			(xy 269.24 228.6) (xy 269.24 227.33)
		)
		(stroke
			(width 0)
			(type default)
		)
	)
	(wire
		(pts
			(xy 54.61 137.16) (xy 66.04 137.16)
		)
		(stroke
			(width 0)
			(type default)
		)
	)
	(wire
		(pts
			(xy 40.64 165.1) (xy 46.99 165.1)
		)
		(stroke
			(width 0)
			(type default)
		)
	)
	(wire
		(pts
			(xy 284.48 156.21) (xy 284.48 154.94)
		)
		(stroke
			(width 0)
			(type default)
		)
	)
	(wire
		(pts
			(xy 54.61 144.78) (xy 99.06 144.78)
		)
		(stroke
			(width 0)
			(type default)
		)
	)
	(wire
		(pts
			(xy 217.17 147.32) (xy 270.51 147.32)
		)
		(stroke
			(width 0)
			(type default)
		)
	)
	(wire
		(pts
			(xy 314.96 101.6) (xy 313.69 101.6)
		)
		(stroke
			(width 0)
			(type default)
		)
	)
	(wire
		(pts
			(xy 171.45 152.4) (xy 171.45 180.34)
		)
		(stroke
			(width 0)
			(type default)
		)
	)
	(wire
		(pts
			(xy 217.17 168.91) (xy 246.38 168.91)
		)
		(stroke
			(width 0)
			(type default)
		)
	)
	(wire
		(pts
			(xy 283.21 137.16) (xy 283.21 138.43)
		)
		(stroke
			(width 0)
			(type default)
		)
	)
	(wire
		(pts
			(xy 66.04 165.1) (xy 66.04 162.56)
		)
		(stroke
			(width 0)
			(type default)
		)
	)
	(wire
		(pts
			(xy 163.83 154.94) (xy 163.83 185.42)
		)
		(stroke
			(width 0)
			(type default)
		)
	)
	(wire
		(pts
			(xy 295.91 72.39) (xy 314.96 72.39)
		)
		(stroke
			(width 0)
			(type default)
		)
	)
	(wire
		(pts
			(xy 217.17 137.16) (xy 270.51 137.16)
		)
		(stroke
			(width 0)
			(type default)
		)
	)
	(wire
		(pts
			(xy 152.4 119.38) (xy 165.1 119.38)
		)
		(stroke
			(width 0)
			(type default)
		)
	)
	(wire
		(pts
			(xy 182.88 210.82) (xy 182.88 209.55)
		)
		(stroke
			(width 0)
			(type default)
		)
	)
	(wire
		(pts
			(xy 260.35 198.12) (xy 260.35 199.39)
		)
		(stroke
			(width 0)
			(type default)
		)
	)
	(wire
		(pts
			(xy 260.35 184.15) (xy 266.7 184.15)
		)
		(stroke
			(width 0)
			(type default)
		)
	)
	(wire
		(pts
			(xy 295.91 69.85) (xy 314.96 69.85)
		)
		(stroke
			(width 0)
			(type default)
		)
	)
	(wire
		(pts
			(xy 269.24 156.21) (xy 269.24 154.94)
		)
		(stroke
			(width 0)
			(type default)
		)
	)
	(wire
		(pts
			(xy 281.94 158.75) (xy 284.48 158.75)
		)
		(stroke
			(width 0)
			(type default)
		)
	)
	(wire
		(pts
			(xy 182.88 194.31) (xy 186.69 194.31)
		)
		(stroke
			(width 0)
			(type default)
		)
	)
	(wire
		(pts
			(xy 283.21 162.56) (xy 283.21 161.29)
		)
		(stroke
			(width 0)
			(type default)
		)
	)
	(wire
		(pts
			(xy 227.33 215.9) (xy 228.6 215.9)
		)
		(stroke
			(width 0)
			(type default)
		)
	)
	(wire
		(pts
			(xy 124.46 121.92) (xy 151.13 121.92)
		)
		(stroke
			(width 0)
			(type default)
		)
	)
	(wire
		(pts
			(xy 186.69 144.78) (xy 186.69 180.34)
		)
		(stroke
			(width 0)
			(type default)
		)
	)
	(wire
		(pts
			(xy 93.98 189.23) (xy 93.98 168.91)
		)
		(stroke
			(width 0)
			(type default)
		)
	)
	(wire
		(pts
			(xy 248.92 166.37) (xy 248.92 184.15)
		)
		(stroke
			(width 0)
			(type default)
		)
	)
	(wire
		(pts
			(xy 171.45 194.31) (xy 179.07 194.31)
		)
		(stroke
			(width 0)
			(type default)
		)
	)
	(wire
		(pts
			(xy 384.81 182.88) (xy 384.81 185.42)
		)
		(stroke
			(width 0)
			(type default)
		)
	)
	(wire
		(pts
			(xy 86.36 78.74) (xy 86.36 81.28)
		)
		(stroke
			(width 0)
			(type default)
		)
	)
	(wire
		(pts
			(xy 328.93 187.96) (xy 339.09 187.96)
		)
		(stroke
			(width 0)
			(type default)
		)
	)
	(wire
		(pts
			(xy 217.17 154.94) (xy 269.24 154.94)
		)
		(stroke
			(width 0)
			(type default)
		)
	)
	(wire
		(pts
			(xy 283.21 153.67) (xy 283.21 152.4)
		)
		(stroke
			(width 0)
			(type default)
		)
	)
	(wire
		(pts
			(xy 46.99 156.21) (xy 46.99 157.48)
		)
		(stroke
			(width 0)
			(type default)
		)
	)
	(wire
		(pts
			(xy 179.07 147.32) (xy 179.07 185.42)
		)
		(stroke
			(width 0)
			(type default)
		)
	)
	(wire
		(pts
			(xy 154.94 194.31) (xy 163.83 194.31)
		)
		(stroke
			(width 0)
			(type default)
		)
	)
	(wire
		(pts
			(xy 269.24 207.01) (xy 269.24 208.28)
		)
		(stroke
			(width 0)
			(type default)
		)
	)
	(wire
		(pts
			(xy 99.06 166.37) (xy 87.63 166.37)
		)
		(stroke
			(width 0)
			(type default)
		)
	)
	(wire
		(pts
			(xy 295.91 50.8) (xy 314.96 50.8)
		)
		(stroke
			(width 0)
			(type default)
		)
	)
	(wire
		(pts
			(xy 74.93 152.4) (xy 74.93 165.1)
		)
		(stroke
			(width 0)
			(type default)
		)
	)
	(wire
		(pts
			(xy 124.46 129.54) (xy 165.1 129.54)
		)
		(stroke
			(width 0)
			(type default)
		)
	)
	(wire
		(pts
			(xy 124.46 168.91) (xy 212.09 168.91)
		)
		(stroke
			(width 0)
			(type default)
		)
	)
	(wire
		(pts
			(xy 347.98 187.96) (xy 358.14 187.96)
		)
		(stroke
			(width 0)
			(type default)
		)
	)
	(wire
		(pts
			(xy 384.81 175.26) (xy 384.81 177.8)
		)
		(stroke
			(width 0)
			(type default)
		)
	)
	(wire
		(pts
			(xy 292.1 179.07) (xy 292.1 191.77)
		)
		(stroke
			(width 0)
			(type default)
		)
	)
	(wire
		(pts
			(xy 27.94 165.1) (xy 30.48 165.1)
		)
		(stroke
			(width 0)
			(type default)
		)
	)
	(wire
		(pts
			(xy 154.94 160.02) (xy 154.94 180.34)
		)
		(stroke
			(width 0)
			(type default)
		)
	)
	(wire
		(pts
			(xy 74.93 139.7) (xy 99.06 139.7)
		)
		(stroke
			(width 0)
			(type default)
		)
	)
	(wire
		(pts
			(xy 171.45 152.4) (xy 214.63 152.4)
		)
		(stroke
			(width 0)
			(type default)
		)
	)
	(wire
		(pts
			(xy 269.24 143.51) (xy 269.24 144.78)
		)
		(stroke
			(width 0)
			(type default)
		)
	)
	(wire
		(pts
			(xy 124.46 154.94) (xy 163.83 154.94)
		)
		(stroke
			(width 0)
			(type default)
		)
	)
	(wire
		(pts
			(xy 179.07 194.31) (xy 182.88 194.31)
		)
		(stroke
			(width 0)
			(type default)
		)
	)
	(wire
		(pts
			(xy 283.21 162.56) (xy 358.14 162.56)
		)
		(stroke
			(width 0)
			(type default)
		)
	)
	(wire
		(pts
			(xy 284.48 139.7) (xy 358.14 139.7)
		)
		(stroke
			(width 0)
			(type default)
		)
	)
	(wire
		(pts
			(xy 186.69 185.42) (xy 186.69 194.31)
		)
		(stroke
			(width 0)
			(type default)
		)
	)
	(wire
		(pts
			(xy 179.07 190.5) (xy 179.07 194.31)
		)
		(stroke
			(width 0)
			(type default)
		)
	)
	(wire
		(pts
			(xy 294.64 170.18) (xy 294.64 171.45)
		)
		(stroke
			(width 0)
			(type default)
		)
	)
	(wire
		(pts
			(xy 260.35 191.77) (xy 260.35 193.04)
		)
		(stroke
			(width 0)
			(type default)
		)
	)
	(wire
		(pts
			(xy 201.93 137.16) (xy 214.63 137.16)
		)
		(stroke
			(width 0)
			(type default)
		)
	)
	(wire
		(pts
			(xy 76.2 86.36) (xy 76.2 90.17)
		)
		(stroke
			(width 0)
			(type default)
		)
	)
	(wire
		(pts
			(xy 201.93 137.16) (xy 201.93 180.34)
		)
		(stroke
			(width 0)
			(type default)
		)
	)
	(wire
		(pts
			(xy 124.46 162.56) (xy 146.05 162.56)
		)
		(stroke
			(width 0)
			(type default)
		)
	)
	(wire
		(pts
			(xy 54.61 127) (xy 66.04 127)
		)
		(stroke
			(width 0)
			(type default)
		)
	)
	(wire
		(pts
			(xy 281.94 156.21) (xy 284.48 156.21)
		)
		(stroke
			(width 0)
			(type default)
		)
	)
	(wire
		(pts
			(xy 306.07 184.15) (xy 298.45 184.15)
		)
		(stroke
			(width 0)
			(type default)
		)
	)
	(wire
		(pts
			(xy 295.91 45.72) (xy 314.96 45.72)
		)
		(stroke
			(width 0)
			(type default)
		)
	)
	(wire
		(pts
			(xy 54.61 139.7) (xy 69.85 139.7)
		)
		(stroke
			(width 0)
			(type default)
		)
	)
	(wire
		(pts
			(xy 256.54 179.07) (xy 256.54 181.61)
		)
		(stroke
			(width 0)
			(type default)
		)
	)
	(wire
		(pts
			(xy 86.36 91.44) (xy 99.06 91.44)
		)
		(stroke
			(width 0)
			(type default)
		)
	)
	(wire
		(pts
			(xy 62.23 165.1) (xy 66.04 165.1)
		)
		(stroke
			(width 0)
			(type default)
		)
	)
	(wire
		(pts
			(xy 194.31 194.31) (xy 201.93 194.31)
		)
		(stroke
			(width 0)
			(type default)
		)
	)
	(wire
		(pts
			(xy 313.69 187.96) (xy 314.96 187.96)
		)
		(stroke
			(width 0)
			(type default)
		)
	)
	(wire
		(pts
			(xy 146.05 162.56) (xy 214.63 162.56)
		)
		(stroke
			(width 0)
			(type default)
		)
	)
	(wire
		(pts
			(xy 194.31 190.5) (xy 194.31 194.31)
		)
		(stroke
			(width 0)
			(type default)
		)
	)
	(wire
		(pts
			(xy 86.36 78.74) (xy 97.79 78.74)
		)
		(stroke
			(width 0)
			(type default)
		)
	)
	(wire
		(pts
			(xy 284.48 160.02) (xy 358.14 160.02)
		)
		(stroke
			(width 0)
			(type default)
		)
	)
	(wire
		(pts
			(xy 275.59 224.79) (xy 295.91 224.79)
		)
		(stroke
			(width 0)
			(type default)
		)
	)
	(wire
		(pts
			(xy 93.98 168.91) (xy 99.06 168.91)
		)
		(stroke
			(width 0)
			(type default)
		)
	)
	(wire
		(pts
			(xy 146.05 162.56) (xy 146.05 185.42)
		)
		(stroke
			(width 0)
			(type default)
		)
	)
	(wire
		(pts
			(xy 54.61 114.3) (xy 69.85 114.3)
		)
		(stroke
			(width 0)
			(type default)
		)
	)
	(wire
		(pts
			(xy 281.94 143.51) (xy 284.48 143.51)
		)
		(stroke
			(width 0)
			(type default)
		)
	)
	(wire
		(pts
			(xy 179.07 147.32) (xy 214.63 147.32)
		)
		(stroke
			(width 0)
			(type default)
		)
	)
	(wire
		(pts
			(xy 97.79 88.9) (xy 97.79 78.74)
		)
		(stroke
			(width 0)
			(type default)
		)
	)
	(wire
		(pts
			(xy 287.02 181.61) (xy 294.64 181.61)
		)
		(stroke
			(width 0)
			(type default)
		)
	)
	(wire
		(pts
			(xy 383.54 182.88) (xy 384.81 182.88)
		)
		(stroke
			(width 0)
			(type default)
		)
	)
	(wire
		(pts
			(xy 265.43 179.07) (xy 265.43 186.69)
		)
		(stroke
			(width 0)
			(type default)
		)
	)
	(wire
		(pts
			(xy 271.78 153.67) (xy 270.51 153.67)
		)
		(stroke
			(width 0)
			(type default)
		)
	)
	(wire
		(pts
			(xy 124.46 152.4) (xy 171.45 152.4)
		)
		(stroke
			(width 0)
			(type default)
		)
	)
	(wire
		(pts
			(xy 284.48 158.75) (xy 284.48 160.02)
		)
		(stroke
			(width 0)
			(type default)
		)
	)
	(wire
		(pts
			(xy 270.51 146.05) (xy 271.78 146.05)
		)
		(stroke
			(width 0)
			(type default)
		)
	)
	(wire
		(pts
			(xy 246.38 168.91) (xy 246.38 181.61)
		)
		(stroke
			(width 0)
			(type default)
		)
	)
	(wire
		(pts
			(xy 314.96 53.34) (xy 313.69 53.34)
		)
		(stroke
			(width 0)
			(type default)
		)
	)
	(wire
		(pts
			(xy 269.24 158.75) (xy 269.24 160.02)
		)
		(stroke
			(width 0)
			(type default)
		)
	)
	(wire
		(pts
			(xy 283.21 161.29) (xy 281.94 161.29)
		)
		(stroke
			(width 0)
			(type default)
		)
	)
	(wire
		(pts
			(xy 269.24 140.97) (xy 271.78 140.97)
		)
		(stroke
			(width 0)
			(type default)
		)
	)
	(wire
		(pts
			(xy 347.98 195.58) (xy 347.98 196.85)
		)
		(stroke
			(width 0)
			(type default)
		)
	)
	(wire
		(pts
			(xy 124.46 96.52) (xy 165.1 96.52)
		)
		(stroke
			(width 0)
			(type default)
		)
	)
	(wire
		(pts
			(xy 344.17 180.34) (xy 358.14 180.34)
		)
		(stroke
			(width 0)
			(type default)
		)
	)
	(wire
		(pts
			(xy 292.1 191.77) (xy 292.1 193.04)
		)
		(stroke
			(width 0)
			(type default)
		)
	)
	(wire
		(pts
			(xy 256.54 172.72) (xy 256.54 173.99)
		)
		(stroke
			(width 0)
			(type default)
		)
	)
	(wire
		(pts
			(xy 88.9 168.91) (xy 93.98 168.91)
		)
		(stroke
			(width 0)
			(type default)
		)
	)
	(wire
		(pts
			(xy 292.1 191.77) (xy 300.99 191.77)
		)
		(stroke
			(width 0)
			(type default)
		)
	)
	(wire
		(pts
			(xy 284.48 154.94) (xy 358.14 154.94)
		)
		(stroke
			(width 0)
			(type default)
		)
	)
	(wire
		(pts
			(xy 308.61 224.79) (xy 323.85 224.79)
		)
		(stroke
			(width 0)
			(type default)
		)
	)
	(wire
		(pts
			(xy 124.46 137.16) (xy 201.93 137.16)
		)
		(stroke
			(width 0)
			(type default)
		)
	)
	(wire
		(pts
			(xy 154.94 160.02) (xy 214.63 160.02)
		)
		(stroke
			(width 0)
			(type default)
		)
	)
	(wire
		(pts
			(xy 295.91 43.18) (xy 314.96 43.18)
		)
		(stroke
			(width 0)
			(type default)
		)
	)
	(text "USE THIN TRACES FOR HIGH INDUCTANCE"
		(exclude_from_sim no)
		(at 142.24 196.85 0)
		(effects
			(font
				(size 1.27 1.27)
			)
			(justify left bottom)
		)
	)
	(text "Note: \n10K internal \npullup\non AB pins "
		(exclude_from_sim no)
		(at 271.78 198.12 0)
		(effects
			(font
				(size 1.27 1.27)
			)
			(justify left bottom)
		)
	)
	(text "HDMI Connector"
		(exclude_from_sim no)
		(at 182.88 66.04 0)
		(effects
			(font
				(size 4 4)
				(thickness 0.5994)
				(bold yes)
			)
			(justify left bottom)
		)
	)
	(label "HDMI_CLK_CONN_N"
		(at 317.5 162.56 0)
		(effects
			(font
				(size 1.27 1.27)
			)
			(justify left bottom)
		)
	)
	(label "HDMI_HPD_5V"
		(at 323.85 224.79 180)
		(effects
			(font
				(size 1.27 1.27)
			)
			(justify right bottom)
		)
	)
	(label "HDMI_D1_N"
		(at 214.63 154.94 180)
		(effects
			(font
				(size 1.27 1.27)
			)
			(justify right bottom)
		)
	)
	(label "HDMI_D0_P"
		(at 217.17 152.4 0)
		(effects
			(font
				(size 1.27 1.27)
			)
			(justify left bottom)
		)
	)
	(label "HDMI_D0_CONN_P"
		(at 295.91 74.93 0)
		(effects
			(font
				(size 1.27 1.27)
			)
			(justify left bottom)
		)
	)
	(label "DP_MUX_D1+"
		(at 82.55 119.38 0)
		(effects
			(font
				(size 1.27 1.27)
			)
			(justify left bottom)
		)
	)
	(label "HDMI_D1_N"
		(at 217.17 147.32 0)
		(effects
			(font
				(size 1.27 1.27)
			)
			(justify left bottom)
		)
	)
	(label "HDMI_HPD_5V"
		(at 295.91 91.44 0)
		(effects
			(font
				(size 1.27 1.27)
			)
			(justify left bottom)
		)
	)
	(label "HDMI_D2_N"
		(at 217.17 139.7 0)
		(effects
			(font
				(size 1.27 1.27)
			)
			(justify left bottom)
		)
	)
	(label "DP_MUX_AUX_A+"
		(at 125.73 166.37 0)
		(effects
			(font
				(size 1.27 1.27)
			)
			(justify left bottom)
		)
	)
	(label "DP_MUX_AUX_A-"
		(at 125.73 168.91 0)
		(effects
			(font
				(size 1.27 1.27)
			)
			(justify left bottom)
		)
	)
	(label "5V_HDMI"
		(at 285.75 170.18 0)
		(effects
			(font
				(size 1.27 1.27)
			)
			(justify left bottom)
		)
	)
	(label "5V_HDMI"
		(at 349.25 187.96 0)
		(effects
			(font
				(size 1.27 1.27)
			)
			(justify left bottom)
		)
	)
	(label "HDMI_D2_CONN_N"
		(at 317.5 139.7 0)
		(effects
			(font
				(size 1.27 1.27)
			)
			(justify left bottom)
		)
	)
	(label "HDMI_D2_P"
		(at 214.63 160.02 180)
		(effects
			(font
				(size 1.27 1.27)
			)
			(justify right bottom)
		)
	)
	(label "HDMI_D0_CONN_P"
		(at 317.5 152.4 0)
		(effects
			(font
				(size 1.27 1.27)
			)
			(justify left bottom)
		)
	)
	(label "HDMI_SCL_3V3"
		(at 232.41 166.37 0)
		(effects
			(font
				(size 1.27 1.27)
			)
			(justify left bottom)
		)
	)
	(label "DP_MUX_D2+"
		(at 82.55 127 0)
		(effects
			(font
				(size 1.27 1.27)
			)
			(justify left bottom)
		)
	)
	(label "DP_MUX_D2-"
		(at 82.55 129.54 0)
		(effects
			(font
				(size 1.27 1.27)
			)
			(justify left bottom)
		)
	)
	(label "HDMI_D0_P"
		(at 214.63 144.78 180)
		(effects
			(font
				(size 1.27 1.27)
			)
			(justify right bottom)
		)
	)
	(label "HDMI_SDA_5V"
		(at 295.91 93.98 0)
		(effects
			(font
				(size 1.27 1.27)
			)
			(justify left bottom)
		)
	)
	(label "HDMI_SDA_3V3"
		(at 232.41 168.91 0)
		(effects
			(font
				(size 1.27 1.27)
			)
			(justify left bottom)
		)
	)
	(label "HDMI_CLK_N"
		(at 217.17 162.56 0)
		(effects
			(font
				(size 1.27 1.27)
			)
			(justify left bottom)
		)
	)
	(label "HDMI_HPD"
		(at 125.73 177.8 0)
		(effects
			(font
				(size 1.27 1.27)
			)
			(justify left bottom)
		)
	)
	(label "DP_MUX_AUX_B-"
		(at 125.73 121.92 0)
		(effects
			(font
				(size 1.27 1.27)
			)
			(justify left bottom)
		)
	)
	(label "HDMI_SCL_5V"
		(at 317.5 167.64 0)
		(effects
			(font
				(size 1.27 1.27)
			)
			(justify left bottom)
		)
	)
	(label "5V_HDMI"
		(at 300.99 191.77 180)
		(effects
			(font
				(size 1.27 1.27)
			)
			(justify right bottom)
		)
	)
	(label "HDMI_SCL_5V"
		(at 295.91 96.52 0)
		(effects
			(font
				(size 1.27 1.27)
			)
			(justify left bottom)
		)
	)
	(label "HDMI_CLK_CONN_P"
		(at 317.5 160.02 0)
		(effects
			(font
				(size 1.27 1.27)
			)
			(justify left bottom)
		)
	)
	(label "DP_MUX_D3+"
		(at 82.55 137.16 0)
		(effects
			(font
				(size 1.27 1.27)
			)
			(justify left bottom)
		)
	)
	(label "HDMI_D2_N"
		(at 214.63 162.56 180)
		(effects
			(font
				(size 1.27 1.27)
			)
			(justify right bottom)
		)
	)
	(label "HDMI_D0_CONN_N"
		(at 317.5 154.94 0)
		(effects
			(font
				(size 1.27 1.27)
			)
			(justify left bottom)
		)
	)
	(label "HDMI_D0_CONN_N"
		(at 295.91 72.39 0)
		(effects
			(font
				(size 1.27 1.27)
			)
			(justify left bottom)
		)
	)
	(label "HDMI_CLK_P"
		(at 214.63 137.16 180)
		(effects
			(font
				(size 1.27 1.27)
			)
			(justify right bottom)
		)
	)
	(label "HDMI_HPD_5V_R"
		(at 290.83 224.79 180)
		(effects
			(font
				(size 1.27 1.27)
			)
			(justify right bottom)
		)
	)
	(label "DP_MUX_D3-"
		(at 82.55 139.7 0)
		(effects
			(font
				(size 1.27 1.27)
			)
			(justify left bottom)
		)
	)
	(label "HDMI_D1_P"
		(at 217.17 144.78 0)
		(effects
			(font
				(size 1.27 1.27)
			)
			(justify left bottom)
		)
	)
	(label "HDMI_CLK_P"
		(at 217.17 160.02 0)
		(effects
			(font
				(size 1.27 1.27)
			)
			(justify left bottom)
		)
	)
	(label "HDMI_D0_N"
		(at 214.63 147.32 180)
		(effects
			(font
				(size 1.27 1.27)
			)
			(justify right bottom)
		)
	)
	(label "DP_MUX_D1-"
		(at 82.55 121.92 0)
		(effects
			(font
				(size 1.27 1.27)
			)
			(justify left bottom)
		)
	)
	(label "DP_MUX_D0+"
		(at 82.55 111.76 0)
		(effects
			(font
				(size 1.27 1.27)
			)
			(justify left bottom)
		)
	)
	(label "DP_MUX_EN"
		(at 86.36 91.44 0)
		(effects
			(font
				(size 1.27 1.27)
			)
			(justify left bottom)
		)
	)
	(label "HDMI_D2_CONN_P"
		(at 295.91 50.8 0)
		(effects
			(font
				(size 1.27 1.27)
			)
			(justify left bottom)
		)
	)
	(label "HDMI_D1_CONN_N"
		(at 295.91 43.18 0)
		(effects
			(font
				(size 1.27 1.27)
			)
			(justify left bottom)
		)
	)
	(label "HDMI_D2_CONN_P"
		(at 317.5 137.16 0)
		(effects
			(font
				(size 1.27 1.27)
			)
			(justify left bottom)
		)
	)
	(label "HDMI_SDA_5V"
		(at 317.5 170.18 0)
		(effects
			(font
				(size 1.27 1.27)
			)
			(justify left bottom)
		)
	)
	(label "HDMI_CEC_5V"
		(at 344.17 175.26 0)
		(effects
			(font
				(size 1.27 1.27)
			)
			(justify left bottom)
		)
	)
	(label "HDMI_D1_CONN_P"
		(at 317.5 144.78 0)
		(effects
			(font
				(size 1.27 1.27)
			)
			(justify left bottom)
		)
	)
	(label "HDMI_CLK_CONN_P"
		(at 295.91 69.85 0)
		(effects
			(font
				(size 1.27 1.27)
			)
			(justify left bottom)
		)
	)
	(label "HDMI_D1_CONN_N"
		(at 317.5 147.32 0)
		(effects
			(font
				(size 1.27 1.27)
			)
			(justify left bottom)
		)
	)
	(label "HDMI_CLK_CONN_N"
		(at 295.91 67.31 0)
		(effects
			(font
				(size 1.27 1.27)
			)
			(justify left bottom)
		)
	)
	(label "DP_MUX_AUX_B+"
		(at 125.73 119.38 0)
		(effects
			(font
				(size 1.27 1.27)
			)
			(justify left bottom)
		)
	)
	(label "HDMI_D2_P"
		(at 217.17 137.16 0)
		(effects
			(font
				(size 1.27 1.27)
			)
			(justify left bottom)
		)
	)
	(label "HDMI_HPD"
		(at 69.85 168.91 0)
		(effects
			(font
				(size 1.27 1.27)
			)
			(justify left bottom)
		)
	)
	(label "HDMI_D1_P"
		(at 214.63 152.4 180)
		(effects
			(font
				(size 1.27 1.27)
			)
			(justify right bottom)
		)
	)
	(label "HDMI_D0_N"
		(at 217.17 154.94 0)
		(effects
			(font
				(size 1.27 1.27)
			)
			(justify left bottom)
		)
	)
	(label "HDMI_D2_CONN_N"
		(at 295.91 48.26 0)
		(effects
			(font
				(size 1.27 1.27)
			)
			(justify left bottom)
		)
	)
	(label "HDMI_HPD_5V"
		(at 344.17 180.34 0)
		(effects
			(font
				(size 1.27 1.27)
			)
			(justify left bottom)
		)
	)
	(label "HDMI_CLK_N"
		(at 214.63 139.7 180)
		(effects
			(font
				(size 1.27 1.27)
			)
			(justify right bottom)
		)
	)
	(label "HDMI_HPD"
		(at 254 215.9 180)
		(effects
			(font
				(size 1.27 1.27)
			)
			(justify right bottom)
		)
	)
	(label "HDMI_D1_CONN_P"
		(at 295.91 45.72 0)
		(effects
			(font
				(size 1.27 1.27)
			)
			(justify left bottom)
		)
	)
	(label "HDMI_CEC_5V"
		(at 295.91 99.06 0)
		(effects
			(font
				(size 1.27 1.27)
			)
			(justify left bottom)
		)
	)
	(label "DP_MUX_D0-"
		(at 82.55 114.3 0)
		(effects
			(font
				(size 1.27 1.27)
			)
			(justify left bottom)
		)
	)
	(global_label "DP1_TXD3_HDMI_TXC_P"
		(shape output)
		(at 54.61 111.76 180)
		(fields_autoplaced yes)
		(effects
			(font
				(size 1.27 1.27)
			)
			(justify right)
		)
		(property "Intersheetrefs" "${INTERSHEET_REFS}"
			(at 30.5464 111.8394 0)
			(effects
				(font
					(size 1.27 1.27)
				)
				(justify right)
			)
		)
	)
	(global_label "DP1_TXD1_HDMI_TX1_P"
		(shape output)
		(at 54.61 127 180)
		(fields_autoplaced yes)
		(effects
			(font
				(size 1.27 1.27)
			)
			(justify right)
		)
		(property "Intersheetrefs" "${INTERSHEET_REFS}"
			(at 30.6069 127.0794 0)
			(effects
				(font
					(size 1.27 1.27)
				)
				(justify right)
			)
		)
	)
	(global_label "DP1_TXD1_N"
		(shape output)
		(at 165.1 106.68 0)
		(effects
			(font
				(size 1.27 1.27)
			)
			(justify left)
		)
		(property "Intersheetrefs" "${INTERSHEET_REFS}"
			(at 179.705 106.68 0)
			(effects
				(font
					(size 1.27 1.27)
				)
				(justify left)
			)
		)
	)
	(global_label "DP1_TXD2_N"
		(shape output)
		(at 165.1 99.06 0)
		(effects
			(font
				(size 1.27 1.27)
			)
			(justify left)
		)
		(property "Intersheetrefs" "${INTERSHEET_REFS}"
			(at 179.705 99.06 0)
			(effects
				(font
					(size 1.27 1.27)
				)
				(justify left)
			)
		)
	)
	(global_label "DP1_TXD2_HDMI_TX0_N"
		(shape output)
		(at 54.61 121.92 180)
		(fields_autoplaced yes)
		(effects
			(font
				(size 1.27 1.27)
			)
			(justify right)
		)
		(property "Intersheetrefs" "${INTERSHEET_REFS}"
			(at 30.5464 121.9994 0)
			(effects
				(font
					(size 1.27 1.27)
				)
				(justify right)
			)
		)
	)
	(global_label "DP1_TXD0_HDMI_TX2_N"
		(shape output)
		(at 54.61 139.7 180)
		(fields_autoplaced yes)
		(effects
			(font
				(size 1.27 1.27)
			)
			(justify right)
		)
		(property "Intersheetrefs" "${INTERSHEET_REFS}"
			(at 30.5464 139.7794 0)
			(effects
				(font
					(size 1.27 1.27)
				)
				(justify right)
			)
		)
	)
	(global_label "DP1_AUX_N"
		(shape output)
		(at 165.1 121.92 0)
		(effects
			(font
				(size 1.27 1.27)
			)
			(justify left)
		)
		(property "Intersheetrefs" "${INTERSHEET_REFS}"
			(at 179.705 121.92 0)
			(effects
				(font
					(size 1.27 1.27)
				)
				(justify left)
			)
		)
	)
	(global_label "DP1_TXD2_HDMI_TX0_P"
		(shape output)
		(at 54.61 119.38 180)
		(fields_autoplaced yes)
		(effects
			(font
				(size 1.27 1.27)
			)
			(justify right)
		)
		(property "Intersheetrefs" "${INTERSHEET_REFS}"
			(at 30.6069 119.4594 0)
			(effects
				(font
					(size 1.27 1.27)
				)
				(justify right)
			)
		)
	)
	(global_label "DP1_HPD"
		(shape output)
		(at 27.94 165.1 180)
		(effects
			(font
				(size 1.27 1.27)
			)
			(justify right)
		)
		(property "Intersheetrefs" "${INTERSHEET_REFS}"
			(at 16.51 165.1 0)
			(effects
				(font
					(size 1.27 1.27)
				)
				(justify right)
			)
		)
	)
	(global_label "DP1_TXD3_P"
		(shape output)
		(at 165.1 88.9 0)
		(effects
			(font
				(size 1.27 1.27)
			)
			(justify left)
		)
		(property "Intersheetrefs" "${INTERSHEET_REFS}"
			(at 179.705 88.9 0)
			(effects
				(font
					(size 1.27 1.27)
				)
				(justify left)
			)
		)
	)
	(global_label "DP1_TXD0_HDMI_TX2_P"
		(shape output)
		(at 54.61 137.16 180)
		(fields_autoplaced yes)
		(effects
			(font
				(size 1.27 1.27)
			)
			(justify right)
		)
		(property "Intersheetrefs" "${INTERSHEET_REFS}"
			(at 30.6069 137.2394 0)
			(effects
				(font
					(size 1.27 1.27)
				)
				(justify right)
			)
		)
	)
	(global_label "DP1_TXD3_HDMI_TXC_N"
		(shape output)
		(at 54.61 114.3 180)
		(fields_autoplaced yes)
		(effects
			(font
				(size 1.27 1.27)
			)
			(justify right)
		)
		(property "Intersheetrefs" "${INTERSHEET_REFS}"
			(at 30.4859 114.3794 0)
			(effects
				(font
					(size 1.27 1.27)
				)
				(justify right)
			)
		)
	)
	(global_label "DP1_TXD2_P"
		(shape output)
		(at 165.1 96.52 0)
		(effects
			(font
				(size 1.27 1.27)
			)
			(justify left)
		)
		(property "Intersheetrefs" "${INTERSHEET_REFS}"
			(at 179.705 96.52 0)
			(effects
				(font
					(size 1.27 1.27)
				)
				(justify left)
			)
		)
	)
	(global_label "DP1_AUX_P"
		(shape output)
		(at 165.1 119.38 0)
		(effects
			(font
				(size 1.27 1.27)
			)
			(justify left)
		)
		(property "Intersheetrefs" "${INTERSHEET_REFS}"
			(at 179.705 119.38 0)
			(effects
				(font
					(size 1.27 1.27)
				)
				(justify left)
			)
		)
	)
	(global_label "USBC_HPD"
		(shape input)
		(at 60.96 198.12 180)
		(effects
			(font
				(size 1.27 1.27)
			)
			(justify right)
		)
		(property "Intersheetrefs" "${INTERSHEET_REFS}"
			(at 46.99 198.12 0)
			(effects
				(font
					(size 1.27 1.27)
				)
				(justify right)
			)
		)
	)
	(global_label "DP1_TXD0_P"
		(shape output)
		(at 165.1 111.76 0)
		(effects
			(font
				(size 1.27 1.27)
			)
			(justify left)
		)
		(property "Intersheetrefs" "${INTERSHEET_REFS}"
			(at 179.705 111.76 0)
			(effects
				(font
					(size 1.27 1.27)
				)
				(justify left)
			)
		)
	)
	(global_label "DP1_HDMI_AUX_P"
		(shape output)
		(at 54.61 144.78 180)
		(fields_autoplaced yes)
		(effects
			(font
				(size 1.27 1.27)
			)
			(justify right)
		)
		(property "Intersheetrefs" "${INTERSHEET_REFS}"
			(at 35.9893 144.7006 0)
			(effects
				(font
					(size 1.27 1.27)
				)
				(justify right)
			)
		)
	)
	(global_label "DP1_TXD3_N"
		(shape output)
		(at 165.1 91.44 0)
		(effects
			(font
				(size 1.27 1.27)
			)
			(justify left)
		)
		(property "Intersheetrefs" "${INTERSHEET_REFS}"
			(at 179.705 91.44 0)
			(effects
				(font
					(size 1.27 1.27)
				)
				(justify left)
			)
		)
	)
	(global_label "DP1_TXD1_P"
		(shape output)
		(at 165.1 104.14 0)
		(effects
			(font
				(size 1.27 1.27)
			)
			(justify left)
		)
		(property "Intersheetrefs" "${INTERSHEET_REFS}"
			(at 179.705 104.14 0)
			(effects
				(font
					(size 1.27 1.27)
				)
				(justify left)
			)
		)
	)
	(global_label "USBC_HPD"
		(shape input)
		(at 165.1 129.54 0)
		(effects
			(font
				(size 1.27 1.27)
			)
			(justify left)
		)
		(property "Intersheetrefs" "${INTERSHEET_REFS}"
			(at 179.07 129.54 0)
			(effects
				(font
					(size 1.27 1.27)
				)
				(justify left)
			)
		)
	)
	(global_label "DP1_TXD1_HDMI_TX1_N"
		(shape output)
		(at 54.61 129.54 180)
		(fields_autoplaced yes)
		(effects
			(font
				(size 1.27 1.27)
			)
			(justify right)
		)
		(property "Intersheetrefs" "${INTERSHEET_REFS}"
			(at 30.5464 129.6194 0)
			(effects
				(font
					(size 1.27 1.27)
				)
				(justify right)
			)
		)
	)
	(global_label "DP1_HDMI_AUX_N"
		(shape output)
		(at 54.61 147.32 180)
		(fields_autoplaced yes)
		(effects
			(font
				(size 1.27 1.27)
			)
			(justify right)
		)
		(property "Intersheetrefs" "${INTERSHEET_REFS}"
			(at 35.9288 147.2406 0)
			(effects
				(font
					(size 1.27 1.27)
				)
				(justify right)
			)
		)
	)
	(global_label "DP1_TXD0_N"
		(shape output)
		(at 165.1 114.3 0)
		(effects
			(font
				(size 1.27 1.27)
			)
			(justify left)
		)
		(property "Intersheetrefs" "${INTERSHEET_REFS}"
			(at 179.705 114.3 0)
			(effects
				(font
					(size 1.27 1.27)
				)
				(justify left)
			)
		)
	)
	(symbol
		(lib_id "antmicroResistors0402:R_10k_0402")
		(at 66.04 162.56 90)
		(unit 1)
		(exclude_from_sim no)
		(in_bom yes)
		(on_board yes)
		(dnp no)
		(property "Reference" "R49"
			(at 67.31 158.75 90)
			(effects
				(font
					(size 1.27 1.27)
				)
				(justify right)
			)
		)
		(property "Value" "R_10k_0402"
			(at 78.74 142.24 0)
			(effects
				(font
					(size 1.27 1.27)
					(thickness 0.15)
				)
				(justify left bottom)
				(hide yes)
			)
		)
		(property "Footprint" "antmicro-footprints:R_0402_1005Metric"
			(at 81.28 142.24 0)
			(effects
				(font
					(size 1.27 1.27)
					(thickness 0.15)
				)
				(justify left bottom)
				(hide yes)
			)
		)
		(property "Datasheet" "https://www.bourns.com/docs/product-datasheets/cr.pdf"
			(at 83.82 142.24 0)
			(effects
				(font
					(size 1.27 1.27)
					(thickness 0.15)
				)
				(justify left bottom)
				(hide yes)
			)
		)
		(property "Description" ""
			(at 66.04 162.56 0)
			(effects
				(font
					(size 1.27 1.27)
				)
				(hide yes)
			)
		)
		(property "Manufacturer" "Bourns"
			(at 88.9 142.24 0)
			(effects
				(font
					(size 1.27 1.27)
					(thickness 0.15)
				)
				(justify left bottom)
				(hide yes)
			)
		)
		(property "MPN" "CR0402-FX-1002GLF"
			(at 86.36 142.24 0)
			(effects
				(font
					(size 1.27 1.27)
					(thickness 0.15)
				)
				(justify left bottom)
				(hide yes)
			)
		)
		(property "Val" "10k"
			(at 67.31 161.29 90)
			(effects
				(font
					(size 1.27 1.27)
					(thickness 0.15)
				)
				(justify right)
			)
		)
		(property "License" "Apache-2.0"
			(at 91.44 142.24 0)
			(effects
				(font
					(size 1.27 1.27)
					(thickness 0.15)
				)
				(justify left bottom)
				(hide yes)
			)
		)
		(property "Author" "Antmicro"
			(at 93.98 142.24 0)
			(effects
				(font
					(size 1.27 1.27)
					(thickness 0.15)
				)
				(justify left bottom)
				(hide yes)
			)
		)
		(property "Tolerance" "1%"
			(at 76.2 142.24 0)
			(effects
				(font
					(size 1.27 1.27)
				)
				(justify left bottom)
				(hide yes)
			)
		)
		(pin "1"
		)
		(pin "2"
		)
		(instances
			(project "jetson-orin-baseboard"
				(path ""
					(reference "R49")
					(unit 1)
				)
			)
		)
	)
	(symbol
		(lib_id "antmicroResistors0402:R_0R_0402")
		(at 212.09 166.37 0)
		(unit 1)
		(exclude_from_sim no)
		(in_bom yes)
		(on_board yes)
		(dnp no)
		(property "Reference" "R277"
			(at 217.17 165.735 0)
			(effects
				(font
					(size 1.27 1.27)
				)
				(justify left bottom)
			)
		)
		(property "Value" "R_0R_0402"
			(at 232.41 179.07 0)
			(effects
				(font
					(size 1.27 1.27)
					(thickness 0.15)
				)
				(justify left bottom)
				(hide yes)
			)
		)
		(property "Footprint" "antmicro-footprints:R_0402_1005Metric"
			(at 232.41 181.61 0)
			(effects
				(font
					(size 1.27 1.27)
					(thickness 0.15)
				)
				(justify left bottom)
				(hide yes)
			)
		)
		(property "Datasheet" "https://industrial.panasonic.com/cdbs/www-data/pdf/RDA0000/AOA0000C301.pdf"
			(at 232.41 184.15 0)
			(effects
				(font
					(size 1.27 1.27)
					(thickness 0.15)
				)
				(justify left bottom)
				(hide yes)
			)
		)
		(property "Description" ""
			(at 212.09 166.37 0)
			(effects
				(font
					(size 1.27 1.27)
				)
				(hide yes)
			)
		)
		(property "Manufacturer" "Panasonic"
			(at 232.41 189.23 0)
			(effects
				(font
					(size 1.27 1.27)
					(thickness 0.15)
				)
				(justify left bottom)
				(hide yes)
			)
		)
		(property "MPN" "ERJ2GE0R00X"
			(at 232.41 186.69 0)
			(effects
				(font
					(size 1.27 1.27)
					(thickness 0.15)
				)
				(justify left bottom)
				(hide yes)
			)
		)
		(property "Val" "0R"
			(at 209.55 165.735 0)
			(effects
				(font
					(size 1.27 1.27)
					(thickness 0.15)
				)
				(justify left bottom)
			)
		)
		(property "License" "Apache-2.0"
			(at 232.41 191.77 0)
			(effects
				(font
					(size 1.27 1.27)
					(thickness 0.15)
				)
				(justify left bottom)
				(hide yes)
			)
		)
		(property "Author" "Antmicro"
			(at 232.41 194.31 0)
			(effects
				(font
					(size 1.27 1.27)
					(thickness 0.15)
				)
				(justify left bottom)
				(hide yes)
			)
		)
		(property "Tolerance" "~"
			(at 232.41 176.53 0)
			(effects
				(font
					(size 1.27 1.27)
				)
				(justify left bottom)
				(hide yes)
			)
		)
		(property "Current" "1A"
			(at 232.41 196.85 0)
			(effects
				(font
					(size 1.27 1.27)
					(thickness 0.15)
				)
				(justify left bottom)
				(hide yes)
			)
		)
		(pin "1"
		)
		(pin "2"
		)
		(instances
			(project "jetson-orin-baseboard"
				(path ""
					(reference "R277")
					(unit 1)
				)
			)
		)
	)
	(symbol
		(lib_id "antmicroResistors0402:R_499R_0402")
		(at 163.83 190.5 90)
		(unit 1)
		(exclude_from_sim no)
		(in_bom yes)
		(on_board yes)
		(dnp no)
		(property "Reference" "R212"
			(at 170.18 186.69 90)
			(effects
				(font
					(size 1.27 1.27)
					(thickness 0.15)
				)
				(justify left)
			)
		)
		(property "Value" "R_499R_0402"
			(at 176.53 170.18 0)
			(effects
				(font
					(size 1.27 1.27)
					(thickness 0.15)
				)
				(justify left bottom)
				(hide yes)
			)
		)
		(property "Footprint" "antmicro-footprints:R_0402_1005Metric"
			(at 179.07 170.18 0)
			(effects
				(font
					(size 1.27 1.27)
					(thickness 0.15)
				)
				(justify left bottom)
				(hide yes)
			)
		)
		(property "Datasheet" "https://www.mouser.com/datasheet/2/54/cr-1858361.pdf"
			(at 181.61 170.18 0)
			(effects
				(font
					(size 1.27 1.27)
					(thickness 0.15)
				)
				(justify left bottom)
				(hide yes)
			)
		)
		(property "Description" ""
			(at 163.83 190.5 0)
			(effects
				(font
					(size 1.27 1.27)
				)
				(hide yes)
			)
		)
		(property "MPN" "CR0402-FX-4990GLF"
			(at 184.15 170.18 0)
			(effects
				(font
					(size 1.27 1.27)
					(thickness 0.15)
				)
				(justify left bottom)
				(hide yes)
			)
		)
		(property "Manufacturer" "Bourns"
			(at 186.69 170.18 0)
			(effects
				(font
					(size 1.27 1.27)
					(thickness 0.15)
				)
				(justify left bottom)
				(hide yes)
			)
		)
		(property "License" "Apache-2.0"
			(at 189.23 170.18 0)
			(effects
				(font
					(size 1.27 1.27)
					(thickness 0.15)
				)
				(justify left bottom)
				(hide yes)
			)
		)
		(property "Author" "Antmicro"
			(at 191.77 170.18 0)
			(effects
				(font
					(size 1.27 1.27)
					(thickness 0.15)
				)
				(justify left bottom)
				(hide yes)
			)
		)
		(property "Val" "499R"
			(at 170.18 189.23 90)
			(effects
				(font
					(size 1.27 1.27)
					(thickness 0.15)
				)
				(justify left)
			)
		)
		(property "Tolerance" "1%"
			(at 173.99 170.18 0)
			(effects
				(font
					(size 1.27 1.27)
				)
				(justify left bottom)
				(hide yes)
			)
		)
		(pin "1"
		)
		(pin "2"
		)
		(instances
			(project "jetson-orin-baseboard"
				(path ""
					(reference "R212")
					(unit 1)
				)
			)
		)
	)
	(symbol
		(lib_id "antmicroCapacitors0402:C_100n_0402")
		(at 74.93 114.3 0)
		(mirror y)
		(unit 1)
		(exclude_from_sim no)
		(in_bom yes)
		(on_board yes)
		(dnp no)
		(property "Reference" "C86"
			(at 73.66 113.665 0)
			(effects
				(font
					(size 1.27 1.27)
				)
				(justify right bottom)
			)
		)
		(property "Value" "C_100n_0402"
			(at 54.61 124.46 0)
			(effects
				(font
					(size 1.27 1.27)
					(thickness 0.15)
				)
				(justify left bottom)
				(hide yes)
			)
		)
		(property "Footprint" "antmicro-footprints:C_0402_1005Metric"
			(at 54.61 127 0)
			(effects
				(font
					(size 1.27 1.27)
					(thickness 0.15)
				)
				(justify left bottom)
				(hide yes)
			)
		)
		(property "Datasheet" "https://www.murata.com/products/productdetail?partno=GRM155R61H104KE14%23"
			(at 54.61 129.54 0)
			(effects
				(font
					(size 1.27 1.27)
					(thickness 0.15)
				)
				(justify left bottom)
				(hide yes)
			)
		)
		(property "Description" ""
			(at 74.93 114.3 0)
			(effects
				(font
					(size 1.27 1.27)
				)
				(hide yes)
			)
		)
		(property "Manufacturer" "Murata"
			(at 54.61 134.62 0)
			(effects
				(font
					(size 1.27 1.27)
					(thickness 0.15)
				)
				(justify left bottom)
				(hide yes)
			)
		)
		(property "MPN" "GRM155R61H104KE14D"
			(at 54.61 132.08 0)
			(effects
				(font
					(size 1.27 1.27)
					(thickness 0.15)
				)
				(justify left bottom)
				(hide yes)
			)
		)
		(property "Val" "100n"
			(at 71.12 116.205 0)
			(effects
				(font
					(size 1.27 1.27)
					(thickness 0.15)
				)
				(justify left bottom)
			)
		)
		(property "License" "Apache-2.0"
			(at 54.61 137.16 0)
			(effects
				(font
					(size 1.27 1.27)
					(thickness 0.15)
				)
				(justify left bottom)
				(hide yes)
			)
		)
		(property "Author" "Antmicro"
			(at 54.61 139.7 0)
			(effects
				(font
					(size 1.27 1.27)
					(thickness 0.15)
				)
				(justify left bottom)
				(hide yes)
			)
		)
		(property "Voltage" "50V"
			(at 54.61 142.24 0)
			(effects
				(font
					(size 1.27 1.27)
				)
				(justify left bottom)
				(hide yes)
			)
		)
		(property "Dielectric" "X5R"
			(at 54.61 144.78 0)
			(effects
				(font
					(size 1.27 1.27)
				)
				(justify left bottom)
				(hide yes)
			)
		)
		(pin "1"
		)
		(pin "2"
		)
		(instances
			(project "jetson-orin-baseboard"
				(path ""
					(reference "C86")
					(unit 1)
				)
			)
		)
	)
	(symbol
		(lib_id "antmicroCapacitors0402:C_100n_0402")
		(at 292.1 198.12 270)
		(mirror x)
		(unit 1)
		(exclude_from_sim no)
		(in_bom yes)
		(on_board yes)
		(dnp no)
		(fields_autoplaced yes)
		(property "Reference" "C164"
			(at 294.64 194.3036 90)
			(effects
				(font
					(size 1.27 1.27)
				)
				(justify left)
			)
		)
		(property "Value" "C_100n_0402"
			(at 281.94 177.8 0)
			(effects
				(font
					(size 1.27 1.27)
					(thickness 0.15)
				)
				(justify left bottom)
				(hide yes)
			)
		)
		(property "Footprint" "antmicro-footprints:C_0402_1005Metric"
			(at 279.4 177.8 0)
			(effects
				(font
					(size 1.27 1.27)
					(thickness 0.15)
				)
				(justify left bottom)
				(hide yes)
			)
		)
		(property "Datasheet" "https://www.murata.com/products/productdetail?partno=GRM155R61H104KE14%23"
			(at 276.86 177.8 0)
			(effects
				(font
					(size 1.27 1.27)
					(thickness 0.15)
				)
				(justify left bottom)
				(hide yes)
			)
		)
		(property "Description" ""
			(at 292.1 198.12 0)
			(effects
				(font
					(size 1.27 1.27)
				)
				(hide yes)
			)
		)
		(property "Manufacturer" "Murata"
			(at 271.78 177.8 0)
			(effects
				(font
					(size 1.27 1.27)
					(thickness 0.15)
				)
				(justify left bottom)
				(hide yes)
			)
		)
		(property "MPN" "GRM155R61H104KE14D"
			(at 274.32 177.8 0)
			(effects
				(font
					(size 1.27 1.27)
					(thickness 0.15)
				)
				(justify left bottom)
				(hide yes)
			)
		)
		(property "Val" "100n"
			(at 294.64 196.8436 90)
			(effects
				(font
					(size 1.27 1.27)
					(thickness 0.15)
				)
				(justify left)
			)
		)
		(property "License" "Apache-2.0"
			(at 269.24 177.8 0)
			(effects
				(font
					(size 1.27 1.27)
					(thickness 0.15)
				)
				(justify left bottom)
				(hide yes)
			)
		)
		(property "Author" "Antmicro"
			(at 266.7 177.8 0)
			(effects
				(font
					(size 1.27 1.27)
					(thickness 0.15)
				)
				(justify left bottom)
				(hide yes)
			)
		)
		(property "Voltage" "50V"
			(at 264.16 177.8 0)
			(effects
				(font
					(size 1.27 1.27)
				)
				(justify left bottom)
				(hide yes)
			)
		)
		(property "Dielectric" "X5R"
			(at 261.62 177.8 0)
			(effects
				(font
					(size 1.27 1.27)
				)
				(justify left bottom)
				(hide yes)
			)
		)
		(pin "1"
		)
		(pin "2"
		)
		(instances
			(project "jetson-orin-baseboard"
				(path ""
					(reference "C164")
					(unit 1)
				)
			)
		)
	)
	(symbol
		(lib_id "antmicroTestPoints:TP_0.75mm_SMD")
		(at 243.84 184.15 180)
		(unit 1)
		(exclude_from_sim no)
		(in_bom no)
		(on_board yes)
		(dnp no)
		(property "Reference" "TP57"
			(at 240.03 184.15 0)
			(effects
				(font
					(size 1.27 1.27)
				)
				(justify left)
			)
		)
		(property "Value" "TP_0.75mm_SMD"
			(at 233.68 180.34 0)
			(effects
				(font
					(size 1.27 1.27)
					(thickness 0.15)
				)
				(justify left bottom)
				(hide yes)
			)
		)
		(property "Footprint" "antmicro-footprints:TP_SMD_0.75mm"
			(at 233.68 177.8 0)
			(effects
				(font
					(size 1.27 1.27)
					(thickness 0.15)
				)
				(justify left bottom)
				(hide yes)
			)
		)
		(property "Datasheet" ""
			(at 226.06 171.45 0)
			(effects
				(font
					(size 1.27 1.27)
					(thickness 0.15)
				)
				(justify left bottom)
				(hide yes)
			)
		)
		(property "Description" ""
			(at 243.84 184.15 0)
			(effects
				(font
					(size 1.27 1.27)
				)
				(hide yes)
			)
		)
		(property "MPN" ""
			(at 233.045 172.72 0)
			(effects
				(font
					(size 1.27 1.27)
					(thickness 0.15)
				)
				(justify left bottom)
				(hide yes)
			)
		)
		(property "Manufacturer" ""
			(at 233.045 177.8 0)
			(effects
				(font
					(size 1.27 1.27)
					(thickness 0.15)
				)
				(justify left bottom)
				(hide yes)
			)
		)
		(property "Author" "Antmicro"
			(at 233.68 175.26 0)
			(effects
				(font
					(size 1.27 1.27)
					(thickness 0.15)
				)
				(justify left bottom)
				(hide yes)
			)
		)
		(property "License" "Apache-2.0"
			(at 233.68 172.72 0)
			(effects
				(font
					(size 1.27 1.27)
					(thickness 0.15)
				)
				(justify left bottom)
				(hide yes)
			)
		)
		(pin "1"
		)
		(instances
			(project "jetson-orin-baseboard"
				(path ""
					(reference "TP57")
					(unit 1)
				)
			)
		)
	)
	(symbol
		(lib_id "antmicropower:GND")
		(at 292.1 199.39 0)
		(unit 1)
		(exclude_from_sim no)
		(in_bom yes)
		(on_board yes)
		(dnp no)
		(property "Reference" "#PWR0298"
			(at 292.1 205.74 0)
			(effects
				(font
					(size 1.27 1.27)
				)
				(justify left bottom)
				(hide yes)
			)
		)
		(property "Value" "GND"
			(at 292.1 203.2 0)
			(effects
				(font
					(size 1.27 1.27)
					(thickness 0.15)
				)
			)
		)
		(property "Footprint" ""
			(at 300.99 207.01 0)
			(effects
				(font
					(size 1.27 1.27)
					(thickness 0.15)
				)
				(justify left bottom)
				(hide yes)
			)
		)
		(property "Datasheet" ""
			(at 300.99 212.09 0)
			(effects
				(font
					(size 1.27 1.27)
					(thickness 0.15)
				)
				(justify left bottom)
				(hide yes)
			)
		)
		(property "Description" ""
			(at 292.1 199.39 0)
			(effects
				(font
					(size 1.27 1.27)
				)
				(hide yes)
			)
		)
		(property "Author" "Antmicro"
			(at 300.99 207.01 0)
			(effects
				(font
					(size 1.27 1.27)
					(thickness 0.15)
				)
				(justify left bottom)
				(hide yes)
			)
		)
		(property "License" "Apache-2.0"
			(at 300.99 209.55 0)
			(effects
				(font
					(size 1.27 1.27)
					(thickness 0.15)
				)
				(justify left bottom)
				(hide yes)
			)
		)
		(pin "1"
		)
		(instances
			(project "jetson-orin-baseboard"
				(path ""
					(reference "#PWR0298")
					(unit 1)
				)
			)
		)
	)
	(symbol
		(lib_id "antmicropower:+3V3")
		(at 76.2 77.47 0)
		(unit 1)
		(exclude_from_sim no)
		(in_bom yes)
		(on_board yes)
		(dnp no)
		(property "Reference" "#PWR015"
			(at 76.2 81.28 0)
			(effects
				(font
					(size 1.27 1.27)
				)
				(justify left bottom)
				(hide yes)
			)
		)
		(property "Value" "+3V3"
			(at 73.025 74.295 0)
			(effects
				(font
					(size 1.27 1.27)
					(thickness 0.15)
				)
				(justify left bottom)
			)
		)
		(property "Footprint" ""
			(at 91.44 85.09 0)
			(effects
				(font
					(size 1.27 1.27)
					(thickness 0.15)
				)
				(justify left bottom)
				(hide yes)
			)
		)
		(property "Datasheet" ""
			(at 91.44 87.63 0)
			(effects
				(font
					(size 1.27 1.27)
					(thickness 0.15)
				)
				(justify left bottom)
				(hide yes)
			)
		)
		(property "Description" ""
			(at 76.2 77.47 0)
			(effects
				(font
					(size 1.27 1.27)
				)
				(hide yes)
			)
		)
		(property "Author" "Antmicro"
			(at 91.44 80.01 0)
			(effects
				(font
					(size 1.27 1.27)
					(thickness 0.15)
				)
				(justify left bottom)
				(hide yes)
			)
		)
		(property "License" "Apache-2.0"
			(at 91.44 82.55 0)
			(effects
				(font
					(size 1.27 1.27)
					(thickness 0.15)
				)
				(justify left bottom)
				(hide yes)
			)
		)
		(pin "1"
		)
		(instances
			(project "jetson-orin-baseboard"
				(path ""
					(reference "#PWR015")
					(unit 1)
				)
			)
		)
	)
	(symbol
		(lib_id "antmicroLogicTranslatorsLevelShifters:NTS0102_XSON")
		(at 266.7 179.07 0)
		(unit 1)
		(exclude_from_sim no)
		(in_bom yes)
		(on_board yes)
		(dnp no)
		(property "Reference" "U43"
			(at 276.86 172.72 0)
			(effects
				(font
					(size 1.27 1.27)
				)
			)
		)
		(property "Value" "NTS0102_XSON"
			(at 302.26 186.69 0)
			(effects
				(font
					(size 1.27 1.27)
					(thickness 0.15)
				)
				(justify left bottom)
				(hide yes)
			)
		)
		(property "Footprint" "antmicro-footprints:XSON-8_1x1.95mm_P0.5mm"
			(at 302.26 189.23 0)
			(effects
				(font
					(size 1.27 1.27)
					(thickness 0.15)
				)
				(justify left bottom)
				(hide yes)
			)
		)
		(property "Datasheet" "http://www.farnell.com/datasheets/1760723.pdf"
			(at 302.26 191.77 0)
			(effects
				(font
					(size 1.27 1.27)
					(thickness 0.15)
				)
				(justify left bottom)
				(hide yes)
			)
		)
		(property "Description" ""
			(at 266.7 179.07 0)
			(effects
				(font
					(size 1.27 1.27)
				)
				(hide yes)
			)
		)
		(property "MPN" "NTS0102GT"
			(at 276.86 175.26 0)
			(effects
				(font
					(size 1.27 1.27)
					(thickness 0.15)
				)
			)
		)
		(property "Manufacturer" "NXP"
			(at 302.26 194.31 0)
			(effects
				(font
					(size 1.27 1.27)
					(thickness 0.15)
				)
				(justify left bottom)
				(hide yes)
			)
		)
		(property "Author" "Antmicro"
			(at 302.26 196.85 0)
			(effects
				(font
					(size 1.27 1.27)
					(thickness 0.15)
				)
				(justify left bottom)
				(hide yes)
			)
		)
		(property "License" "Apache-2.0"
			(at 302.26 199.39 0)
			(effects
				(font
					(size 1.27 1.27)
					(thickness 0.15)
				)
				(justify left bottom)
				(hide yes)
			)
		)
		(pin "1"
		)
		(pin "2"
		)
		(pin "3"
		)
		(pin "4"
		)
		(pin "5"
		)
		(pin "6"
		)
		(pin "7"
		)
		(pin "8"
		)
		(instances
			(project "jetson-orin-baseboard"
				(path ""
					(reference "U43")
					(unit 1)
				)
			)
		)
	)
	(symbol
		(lib_id "antmicroCapacitors0402:C_100n_0402")
		(at 71.12 119.38 0)
		(mirror y)
		(unit 1)
		(exclude_from_sim no)
		(in_bom yes)
		(on_board yes)
		(dnp no)
		(property "Reference" "C132"
			(at 69.85 118.745 0)
			(effects
				(font
					(size 1.27 1.27)
				)
				(justify right bottom)
			)
		)
		(property "Value" "C_100n_0402"
			(at 50.8 129.54 0)
			(effects
				(font
					(size 1.27 1.27)
					(thickness 0.15)
				)
				(justify left bottom)
				(hide yes)
			)
		)
		(property "Footprint" "antmicro-footprints:C_0402_1005Metric"
			(at 50.8 132.08 0)
			(effects
				(font
					(size 1.27 1.27)
					(thickness 0.15)
				)
				(justify left bottom)
				(hide yes)
			)
		)
		(property "Datasheet" "https://www.murata.com/products/productdetail?partno=GRM155R61H104KE14%23"
			(at 50.8 134.62 0)
			(effects
				(font
					(size 1.27 1.27)
					(thickness 0.15)
				)
				(justify left bottom)
				(hide yes)
			)
		)
		(property "Description" ""
			(at 71.12 119.38 0)
			(effects
				(font
					(size 1.27 1.27)
				)
				(hide yes)
			)
		)
		(property "Manufacturer" "Murata"
			(at 50.8 139.7 0)
			(effects
				(font
					(size 1.27 1.27)
					(thickness 0.15)
				)
				(justify left bottom)
				(hide yes)
			)
		)
		(property "MPN" "GRM155R61H104KE14D"
			(at 50.8 137.16 0)
			(effects
				(font
					(size 1.27 1.27)
					(thickness 0.15)
				)
				(justify left bottom)
				(hide yes)
			)
		)
		(property "Val" "100n"
			(at 67.31 121.285 0)
			(effects
				(font
					(size 1.27 1.27)
					(thickness 0.15)
				)
				(justify left bottom)
			)
		)
		(property "License" "Apache-2.0"
			(at 50.8 142.24 0)
			(effects
				(font
					(size 1.27 1.27)
					(thickness 0.15)
				)
				(justify left bottom)
				(hide yes)
			)
		)
		(property "Author" "Antmicro"
			(at 50.8 144.78 0)
			(effects
				(font
					(size 1.27 1.27)
					(thickness 0.15)
				)
				(justify left bottom)
				(hide yes)
			)
		)
		(property "Voltage" "50V"
			(at 50.8 147.32 0)
			(effects
				(font
					(size 1.27 1.27)
				)
				(justify left bottom)
				(hide yes)
			)
		)
		(property "Dielectric" "X5R"
			(at 50.8 149.86 0)
			(effects
				(font
					(size 1.27 1.27)
				)
				(justify left bottom)
				(hide yes)
			)
		)
		(pin "1"
		)
		(pin "2"
		)
		(instances
			(project "jetson-orin-baseboard"
				(path ""
					(reference "C132")
					(unit 1)
				)
			)
		)
	)
	(symbol
		(lib_id "antmicropower:GND")
		(at 313.69 78.74 0)
		(unit 1)
		(exclude_from_sim no)
		(in_bom yes)
		(on_board yes)
		(dnp no)
		(property "Reference" "#PWR0279"
			(at 313.69 85.09 0)
			(effects
				(font
					(size 1.27 1.27)
				)
				(justify left bottom)
				(hide yes)
			)
		)
		(property "Value" "GND"
			(at 313.69 82.55 0)
			(effects
				(font
					(size 1.27 1.27)
					(thickness 0.15)
				)
			)
		)
		(property "Footprint" ""
			(at 322.58 86.36 0)
			(effects
				(font
					(size 1.27 1.27)
					(thickness 0.15)
				)
				(justify left bottom)
				(hide yes)
			)
		)
		(property "Datasheet" ""
			(at 322.58 91.44 0)
			(effects
				(font
					(size 1.27 1.27)
					(thickness 0.15)
				)
				(justify left bottom)
				(hide yes)
			)
		)
		(property "Description" ""
			(at 313.69 78.74 0)
			(effects
				(font
					(size 1.27 1.27)
				)
				(hide yes)
			)
		)
		(property "Author" "Antmicro"
			(at 322.58 86.36 0)
			(effects
				(font
					(size 1.27 1.27)
					(thickness 0.15)
				)
				(justify left bottom)
				(hide yes)
			)
		)
		(property "License" "Apache-2.0"
			(at 322.58 88.9 0)
			(effects
				(font
					(size 1.27 1.27)
					(thickness 0.15)
				)
				(justify left bottom)
				(hide yes)
			)
		)
		(pin "1"
		)
		(instances
			(project "jetson-orin-baseboard"
				(path ""
					(reference "#PWR0279")
					(unit 1)
				)
			)
		)
	)
	(symbol
		(lib_id "antmicroResistors0402:R_10k_0402")
		(at 86.36 86.36 90)
		(unit 1)
		(exclude_from_sim no)
		(in_bom yes)
		(on_board yes)
		(dnp no)
		(property "Reference" "R160"
			(at 87.63 82.55 90)
			(effects
				(font
					(size 1.27 1.27)
				)
				(justify right)
			)
		)
		(property "Value" "R_10k_0402"
			(at 99.06 66.04 0)
			(effects
				(font
					(size 1.27 1.27)
					(thickness 0.15)
				)
				(justify left bottom)
				(hide yes)
			)
		)
		(property "Footprint" "antmicro-footprints:R_0402_1005Metric"
			(at 101.6 66.04 0)
			(effects
				(font
					(size 1.27 1.27)
					(thickness 0.15)
				)
				(justify left bottom)
				(hide yes)
			)
		)
		(property "Datasheet" "https://www.bourns.com/docs/product-datasheets/cr.pdf"
			(at 104.14 66.04 0)
			(effects
				(font
					(size 1.27 1.27)
					(thickness 0.15)
				)
				(justify left bottom)
				(hide yes)
			)
		)
		(property "Description" ""
			(at 86.36 86.36 0)
			(effects
				(font
					(size 1.27 1.27)
				)
				(hide yes)
			)
		)
		(property "Manufacturer" "Bourns"
			(at 109.22 66.04 0)
			(effects
				(font
					(size 1.27 1.27)
					(thickness 0.15)
				)
				(justify left bottom)
				(hide yes)
			)
		)
		(property "MPN" "CR0402-FX-1002GLF"
			(at 106.68 66.04 0)
			(effects
				(font
					(size 1.27 1.27)
					(thickness 0.15)
				)
				(justify left bottom)
				(hide yes)
			)
		)
		(property "Val" "10k"
			(at 87.63 85.09 90)
			(effects
				(font
					(size 1.27 1.27)
					(thickness 0.15)
				)
				(justify right)
			)
		)
		(property "License" "Apache-2.0"
			(at 111.76 66.04 0)
			(effects
				(font
					(size 1.27 1.27)
					(thickness 0.15)
				)
				(justify left bottom)
				(hide yes)
			)
		)
		(property "Author" "Antmicro"
			(at 114.3 66.04 0)
			(effects
				(font
					(size 1.27 1.27)
					(thickness 0.15)
				)
				(justify left bottom)
				(hide yes)
			)
		)
		(property "Tolerance" "1%"
			(at 96.52 66.04 0)
			(effects
				(font
					(size 1.27 1.27)
				)
				(justify left bottom)
				(hide yes)
			)
		)
		(pin "1"
		)
		(pin "2"
		)
		(instances
			(project "jetson-orin-baseboard"
				(path ""
					(reference "R160")
					(unit 1)
				)
			)
		)
	)
	(symbol
		(lib_id "antmicropower:GND")
		(at 76.2 201.93 0)
		(unit 1)
		(exclude_from_sim no)
		(in_bom yes)
		(on_board yes)
		(dnp no)
		(property "Reference" "#PWR0285"
			(at 76.2 208.28 0)
			(effects
				(font
					(size 1.27 1.27)
				)
				(justify left bottom)
				(hide yes)
			)
		)
		(property "Value" "GND"
			(at 76.2 205.74 0)
			(effects
				(font
					(size 1.27 1.27)
					(thickness 0.15)
				)
			)
		)
		(property "Footprint" ""
			(at 85.09 209.55 0)
			(effects
				(font
					(size 1.27 1.27)
					(thickness 0.15)
				)
				(justify left bottom)
				(hide yes)
			)
		)
		(property "Datasheet" ""
			(at 85.09 214.63 0)
			(effects
				(font
					(size 1.27 1.27)
					(thickness 0.15)
				)
				(justify left bottom)
				(hide yes)
			)
		)
		(property "Description" ""
			(at 76.2 201.93 0)
			(effects
				(font
					(size 1.27 1.27)
				)
				(hide yes)
			)
		)
		(property "Author" "Antmicro"
			(at 85.09 209.55 0)
			(effects
				(font
					(size 1.27 1.27)
					(thickness 0.15)
				)
				(justify left bottom)
				(hide yes)
			)
		)
		(property "License" "Apache-2.0"
			(at 85.09 212.09 0)
			(effects
				(font
					(size 1.27 1.27)
					(thickness 0.15)
				)
				(justify left bottom)
				(hide yes)
			)
		)
		(pin "1"
		)
		(instances
			(project "jetson-orin-baseboard"
				(path ""
					(reference "#PWR0285")
					(unit 1)
				)
			)
		)
	)
	(symbol
		(lib_id "antmicroTransistorsFETsMOSFETsSingle:PJE138K")
		(at 54.61 158.75 270)
		(unit 1)
		(exclude_from_sim no)
		(in_bom yes)
		(on_board yes)
		(dnp no)
		(fields_autoplaced yes)
		(property "Reference" "Q1"
			(at 57.15 168.91 90)
			(effects
				(font
					(size 1.27 1.27)
					(thickness 0.15)
				)
			)
		)
		(property "Value" "PJE138K"
			(at 45.72 181.61 0)
			(effects
				(font
					(size 1.27 1.27)
					(thickness 0.15)
				)
				(justify left bottom)
				(hide yes)
			)
		)
		(property "Footprint" "antmicro-footprints:SOT-523"
			(at 43.18 181.61 0)
			(effects
				(font
					(size 1.27 1.27)
					(thickness 0.15)
				)
				(justify left bottom)
				(hide yes)
			)
		)
		(property "Datasheet" "https://www.mouser.com/datasheet/2/1057/PJE138K-1876698.pdf"
			(at 40.64 181.61 0)
			(effects
				(font
					(size 1.27 1.27)
					(thickness 0.15)
				)
				(justify left bottom)
				(hide yes)
			)
		)
		(property "Description" ""
			(at 54.61 158.75 0)
			(effects
				(font
					(size 1.27 1.27)
				)
				(hide yes)
			)
		)
		(property "MPN" "PJE138K_R1_00001"
			(at 57.15 171.45 90)
			(effects
				(font
					(size 1.27 1.27)
					(thickness 0.15)
				)
			)
		)
		(property "Manufacturer" "PANJIT"
			(at 35.56 181.61 0)
			(effects
				(font
					(size 1.27 1.27)
					(thickness 0.15)
				)
				(justify left bottom)
				(hide yes)
			)
		)
		(property "Author" "Antmicro"
			(at 33.02 181.61 0)
			(effects
				(font
					(size 1.27 1.27)
					(thickness 0.15)
				)
				(justify left bottom)
				(hide yes)
			)
		)
		(property "License" "Apache-2.0"
			(at 30.48 181.61 0)
			(effects
				(font
					(size 1.27 1.27)
					(thickness 0.15)
				)
				(justify left bottom)
				(hide yes)
			)
		)
		(pin "2"
		)
		(pin "3"
		)
		(pin "1"
		)
		(instances
			(project "jetson-orin-baseboard"
				(path ""
					(reference "Q1")
					(unit 1)
				)
			)
		)
	)
	(symbol
		(lib_id "antmicropower:GND")
		(at 313.69 54.61 0)
		(unit 1)
		(exclude_from_sim no)
		(in_bom yes)
		(on_board yes)
		(dnp no)
		(property "Reference" "#PWR0278"
			(at 313.69 60.96 0)
			(effects
				(font
					(size 1.27 1.27)
				)
				(justify left bottom)
				(hide yes)
			)
		)
		(property "Value" "GND"
			(at 313.69 58.42 0)
			(effects
				(font
					(size 1.27 1.27)
					(thickness 0.15)
				)
			)
		)
		(property "Footprint" ""
			(at 322.58 62.23 0)
			(effects
				(font
					(size 1.27 1.27)
					(thickness 0.15)
				)
				(justify left bottom)
				(hide yes)
			)
		)
		(property "Datasheet" ""
			(at 322.58 67.31 0)
			(effects
				(font
					(size 1.27 1.27)
					(thickness 0.15)
				)
				(justify left bottom)
				(hide yes)
			)
		)
		(property "Description" ""
			(at 313.69 54.61 0)
			(effects
				(font
					(size 1.27 1.27)
				)
				(hide yes)
			)
		)
		(property "Author" "Antmicro"
			(at 322.58 62.23 0)
			(effects
				(font
					(size 1.27 1.27)
					(thickness 0.15)
				)
				(justify left bottom)
				(hide yes)
			)
		)
		(property "License" "Apache-2.0"
			(at 322.58 64.77 0)
			(effects
				(font
					(size 1.27 1.27)
					(thickness 0.15)
				)
				(justify left bottom)
				(hide yes)
			)
		)
		(pin "1"
		)
		(instances
			(project "jetson-orin-baseboard"
				(path ""
					(reference "#PWR0278")
					(unit 1)
				)
			)
		)
	)
	(symbol
		(lib_id "antmicropower:+3V3")
		(at 269.24 207.01 0)
		(unit 1)
		(exclude_from_sim no)
		(in_bom yes)
		(on_board yes)
		(dnp no)
		(property "Reference" "#PWR0105"
			(at 269.24 210.82 0)
			(effects
				(font
					(size 1.27 1.27)
				)
				(justify left bottom)
				(hide yes)
			)
		)
		(property "Value" "+3V3"
			(at 266.065 203.2 0)
			(effects
				(font
					(size 1.27 1.27)
					(thickness 0.15)
				)
				(justify left)
			)
		)
		(property "Footprint" ""
			(at 284.48 214.63 0)
			(effects
				(font
					(size 1.27 1.27)
					(thickness 0.15)
				)
				(justify left bottom)
				(hide yes)
			)
		)
		(property "Datasheet" ""
			(at 284.48 217.17 0)
			(effects
				(font
					(size 1.27 1.27)
					(thickness 0.15)
				)
				(justify left bottom)
				(hide yes)
			)
		)
		(property "Description" ""
			(at 269.24 207.01 0)
			(effects
				(font
					(size 1.27 1.27)
				)
				(hide yes)
			)
		)
		(property "Author" "Antmicro"
			(at 284.48 209.55 0)
			(effects
				(font
					(size 1.27 1.27)
					(thickness 0.15)
				)
				(justify left bottom)
				(hide yes)
			)
		)
		(property "License" "Apache-2.0"
			(at 284.48 212.09 0)
			(effects
				(font
					(size 1.27 1.27)
					(thickness 0.15)
				)
				(justify left bottom)
				(hide yes)
			)
		)
		(pin "1"
		)
		(instances
			(project "jetson-orin-baseboard"
				(path ""
					(reference "#PWR0105")
					(unit 1)
				)
			)
		)
	)
	(symbol
		(lib_id "antmicropower:GND")
		(at 76.2 90.17 0)
		(unit 1)
		(exclude_from_sim no)
		(in_bom yes)
		(on_board yes)
		(dnp no)
		(property "Reference" "#PWR019"
			(at 76.2 96.52 0)
			(effects
				(font
					(size 1.27 1.27)
				)
				(justify left bottom)
				(hide yes)
			)
		)
		(property "Value" "GND"
			(at 76.2 93.98 0)
			(effects
				(font
					(size 1.27 1.27)
					(thickness 0.15)
				)
			)
		)
		(property "Footprint" ""
			(at 85.09 97.79 0)
			(effects
				(font
					(size 1.27 1.27)
					(thickness 0.15)
				)
				(justify left bottom)
				(hide yes)
			)
		)
		(property "Datasheet" ""
			(at 85.09 102.87 0)
			(effects
				(font
					(size 1.27 1.27)
					(thickness 0.15)
				)
				(justify left bottom)
				(hide yes)
			)
		)
		(property "Description" ""
			(at 76.2 90.17 0)
			(effects
				(font
					(size 1.27 1.27)
				)
				(hide yes)
			)
		)
		(property "Author" "Antmicro"
			(at 85.09 97.79 0)
			(effects
				(font
					(size 1.27 1.27)
					(thickness 0.15)
				)
				(justify left bottom)
				(hide yes)
			)
		)
		(property "License" "Apache-2.0"
			(at 85.09 100.33 0)
			(effects
				(font
					(size 1.27 1.27)
					(thickness 0.15)
				)
				(justify left bottom)
				(hide yes)
			)
		)
		(pin "1"
		)
		(instances
			(project "jetson-orin-baseboard"
				(path ""
					(reference "#PWR019")
					(unit 1)
				)
			)
		)
	)
	(symbol
		(lib_id "antmicroResistorNetworksArrays:R_4x0R_0201_array")
		(at 281.94 161.29 180)
		(unit 1)
		(exclude_from_sim no)
		(in_bom yes)
		(on_board yes)
		(dnp no)
		(property "Reference" "R34"
			(at 276.86 148.59 0)
			(effects
				(font
					(size 1.27 1.27)
				)
			)
		)
		(property "Value" "R_4x0R_0201_array"
			(at 255.27 153.67 0)
			(effects
				(font
					(size 1.27 1.27)
					(thickness 0.15)
				)
				(justify left bottom)
				(hide yes)
			)
		)
		(property "Footprint" "antmicro-footprints:R_Array_4x0201_Panasonic_EXB18V"
			(at 255.27 148.59 0)
			(effects
				(font
					(size 1.27 1.27)
					(thickness 0.15)
				)
				(justify left bottom)
				(hide yes)
			)
		)
		(property "Datasheet" "http://industrial.panasonic.com/cdbs/www-data/pdf/AOC0000/AOC0000C14.pdf"
			(at 255.27 146.05 0)
			(effects
				(font
					(size 1.27 1.27)
					(thickness 0.15)
				)
				(justify left bottom)
				(hide yes)
			)
		)
		(property "Description" ""
			(at 281.94 161.29 0)
			(effects
				(font
					(size 1.27 1.27)
				)
				(hide yes)
			)
		)
		(property "MPN" "EXB-18VR000X"
			(at 255.27 143.51 0)
			(effects
				(font
					(size 1.27 1.27)
					(thickness 0.15)
				)
				(justify left bottom)
				(hide yes)
			)
		)
		(property "Manufacturer" "Panasonic"
			(at 255.27 140.97 0)
			(effects
				(font
					(size 1.27 1.27)
					(thickness 0.15)
				)
				(justify left bottom)
				(hide yes)
			)
		)
		(property "Val" "4x0R_0201"
			(at 276.86 150.495 0)
			(effects
				(font
					(size 1.27 1.27)
					(thickness 0.15)
				)
			)
		)
		(property "Author" "Antmicro"
			(at 255.27 138.43 0)
			(effects
				(font
					(size 1.27 1.27)
					(thickness 0.15)
				)
				(justify left bottom)
				(hide yes)
			)
		)
		(property "License" "Apache-2.0"
			(at 255.27 135.89 0)
			(effects
				(font
					(size 1.27 1.27)
					(thickness 0.15)
				)
				(justify left bottom)
				(hide yes)
			)
		)
		(pin "1"
		)
		(pin "2"
		)
		(pin "3"
		)
		(pin "4"
		)
		(pin "5"
		)
		(pin "6"
		)
		(pin "7"
		)
		(pin "8"
		)
		(instances
			(project "jetson-orin-baseboard"
				(path ""
					(reference "R34")
					(unit 1)
				)
			)
		)
	)
	(symbol
		(lib_id "antmicroResistors0402:R_10k_0402")
		(at 76.2 186.69 90)
		(unit 1)
		(exclude_from_sim no)
		(in_bom no)
		(on_board yes)
		(dnp yes)
		(property "Reference" "R228"
			(at 77.47 182.88 90)
			(effects
				(font
					(size 1.27 1.27)
				)
				(justify right)
			)
		)
		(property "Value" "R_10k_0402"
			(at 88.9 166.37 0)
			(effects
				(font
					(size 1.27 1.27)
					(thickness 0.15)
				)
				(justify left bottom)
				(hide yes)
			)
		)
		(property "Footprint" "antmicro-footprints:R_0402_1005Metric"
			(at 91.44 166.37 0)
			(effects
				(font
					(size 1.27 1.27)
					(thickness 0.15)
				)
				(justify left bottom)
				(hide yes)
			)
		)
		(property "Datasheet" "https://www.bourns.com/docs/product-datasheets/cr.pdf"
			(at 93.98 166.37 0)
			(effects
				(font
					(size 1.27 1.27)
					(thickness 0.15)
				)
				(justify left bottom)
				(hide yes)
			)
		)
		(property "Description" ""
			(at 76.2 186.69 0)
			(effects
				(font
					(size 1.27 1.27)
				)
				(hide yes)
			)
		)
		(property "Manufacturer" "Bourns"
			(at 99.06 166.37 0)
			(effects
				(font
					(size 1.27 1.27)
					(thickness 0.15)
				)
				(justify left bottom)
				(hide yes)
			)
		)
		(property "MPN" "CR0402-FX-1002GLF"
			(at 96.52 166.37 0)
			(effects
				(font
					(size 1.27 1.27)
					(thickness 0.15)
				)
				(justify left bottom)
				(hide yes)
			)
		)
		(property "Val" "10k"
			(at 77.47 185.42 90)
			(effects
				(font
					(size 1.27 1.27)
					(thickness 0.15)
				)
				(justify right)
			)
		)
		(property "License" "Apache-2.0"
			(at 101.6 166.37 0)
			(effects
				(font
					(size 1.27 1.27)
					(thickness 0.15)
				)
				(justify left bottom)
				(hide yes)
			)
		)
		(property "Author" "Antmicro"
			(at 104.14 166.37 0)
			(effects
				(font
					(size 1.27 1.27)
					(thickness 0.15)
				)
				(justify left bottom)
				(hide yes)
			)
		)
		(property "Tolerance" "1%"
			(at 86.36 166.37 0)
			(effects
				(font
					(size 1.27 1.27)
				)
				(justify left bottom)
				(hide yes)
			)
		)
		(pin "1"
		)
		(pin "2"
		)
		(instances
			(project "jetson-orin-baseboard"
				(path ""
					(reference "R228")
					(unit 1)
				)
			)
		)
	)
	(symbol
		(lib_id "antmicroFerriteBeadsandChips:FB_220Z_2A_Murata-BLM21PG_0805")
		(at 314.96 187.96 0)
		(unit 1)
		(exclude_from_sim no)
		(in_bom yes)
		(on_board yes)
		(dnp no)
		(property "Reference" "FB4"
			(at 317.5 191.77 0)
			(effects
				(font
					(size 1.27 1.27)
				)
			)
		)
		(property "Value" "FB_220Z_2A_Murata-BLM21PG_0805"
			(at 328.93 190.5 0)
			(effects
				(font
					(size 1.27 1.27)
					(thickness 0.15)
				)
				(justify left bottom)
				(hide yes)
			)
		)
		(property "Footprint" "antmicro-footprints:FB_0805_2012Metric"
			(at 328.93 195.58 0)
			(effects
				(font
					(size 1.27 1.27)
					(thickness 0.15)
				)
				(justify left bottom)
				(hide yes)
			)
		)
		(property "Datasheet" "https://www.murata.com/products/productdata/8796738977822/ENFA0005.pdf?1653276712000"
			(at 328.93 198.12 0)
			(effects
				(font
					(size 1.27 1.27)
					(thickness 0.15)
				)
				(justify left bottom)
				(hide yes)
			)
		)
		(property "Description" ""
			(at 314.96 187.96 0)
			(effects
				(font
					(size 1.27 1.27)
				)
				(hide yes)
			)
		)
		(property "MPN" "BLM21PG221SN1D"
			(at 328.93 200.66 0)
			(effects
				(font
					(size 1.27 1.27)
					(thickness 0.15)
				)
				(justify left bottom)
				(hide yes)
			)
		)
		(property "Manufacturer" "Murata"
			(at 328.93 203.2 0)
			(effects
				(font
					(size 1.27 1.27)
					(thickness 0.15)
				)
				(justify left bottom)
				(hide yes)
			)
		)
		(property "Author" "Antmicro"
			(at 328.93 205.74 0)
			(effects
				(font
					(size 1.27 1.27)
					(thickness 0.15)
				)
				(justify left bottom)
				(hide yes)
			)
		)
		(property "License" "Apache-2.0"
			(at 328.93 208.28 0)
			(effects
				(font
					(size 1.27 1.27)
					(thickness 0.15)
				)
				(justify left bottom)
				(hide yes)
			)
		)
		(property "Val" "220Z/2A"
			(at 317.5 194.31 0)
			(effects
				(font
					(size 1.27 1.27)
				)
			)
		)
		(property "Current" ""
			(at 335.28 210.82 0)
			(effects
				(font
					(size 1.27 1.27)
					(thickness 0.15)
				)
				(justify left bottom)
				(hide yes)
			)
		)
		(pin "1"
		)
		(pin "2"
		)
		(instances
			(project "jetson-orin-baseboard"
				(path ""
					(reference "FB4")
					(unit 1)
				)
			)
		)
	)
	(symbol
		(lib_id "antmicroTestPoints:TP_0.75mm_SMD")
		(at 227.33 215.9 180)
		(unit 1)
		(exclude_from_sim no)
		(in_bom no)
		(on_board yes)
		(dnp no)
		(property "Reference" "TP22"
			(at 223.52 215.9 0)
			(effects
				(font
					(size 1.27 1.27)
				)
				(justify left)
			)
		)
		(property "Value" "TP_0.75mm_SMD"
			(at 217.17 212.09 0)
			(effects
				(font
					(size 1.27 1.27)
					(thickness 0.15)
				)
				(justify left bottom)
				(hide yes)
			)
		)
		(property "Footprint" "antmicro-footprints:TP_SMD_0.75mm"
			(at 217.17 209.55 0)
			(effects
				(font
					(size 1.27 1.27)
					(thickness 0.15)
				)
				(justify left bottom)
				(hide yes)
			)
		)
		(property "Datasheet" ""
			(at 209.55 203.2 0)
			(effects
				(font
					(size 1.27 1.27)
					(thickness 0.15)
				)
				(justify left bottom)
				(hide yes)
			)
		)
		(property "Description" ""
			(at 227.33 215.9 0)
			(effects
				(font
					(size 1.27 1.27)
				)
				(hide yes)
			)
		)
		(property "MPN" ""
			(at 216.535 204.47 0)
			(effects
				(font
					(size 1.27 1.27)
					(thickness 0.15)
				)
				(justify left bottom)
				(hide yes)
			)
		)
		(property "Manufacturer" ""
			(at 216.535 209.55 0)
			(effects
				(font
					(size 1.27 1.27)
					(thickness 0.15)
				)
				(justify left bottom)
				(hide yes)
			)
		)
		(property "Author" "Antmicro"
			(at 217.17 207.01 0)
			(effects
				(font
					(size 1.27 1.27)
					(thickness 0.15)
				)
				(justify left bottom)
				(hide yes)
			)
		)
		(property "License" "Apache-2.0"
			(at 217.17 204.47 0)
			(effects
				(font
					(size 1.27 1.27)
					(thickness 0.15)
				)
				(justify left bottom)
				(hide yes)
			)
		)
		(pin "1"
		)
		(instances
			(project "jetson-orin-baseboard"
				(path ""
					(reference "TP22")
					(unit 1)
				)
			)
		)
	)
	(symbol
		(lib_id "antmicroTVSDiodes:TPD4E05U06QDQARQ1")
		(at 314.96 67.31 0)
		(unit 1)
		(exclude_from_sim no)
		(in_bom yes)
		(on_board yes)
		(dnp no)
		(fields_autoplaced yes)
		(property "Reference" "U45"
			(at 325.12 70.485 0)
			(effects
				(font
					(size 1.27 1.27)
				)
				(justify left)
			)
		)
		(property "Value" "TPD4E05U06QDQARQ1"
			(at 339.09 77.47 0)
			(effects
				(font
					(size 1.27 1.27)
					(thickness 0.15)
				)
				(justify left bottom)
				(hide yes)
			)
		)
		(property "Footprint" "antmicro-footprints:USON-10_2.5x1mm_P0.5mm"
			(at 339.09 72.39 0)
			(effects
				(font
					(size 1.27 1.27)
					(thickness 0.15)
				)
				(justify left bottom)
				(hide yes)
			)
		)
		(property "Datasheet" "https://www.ti.com/lit/ds/symlink/tpd4e05u06-q1.pdf?HQS=dis-mous-null-mousermode-dsf-pf-null-wwe&ts=1663591265741&ref_url=https%253A%252F%252Fwww.mouser.com%252F"
			(at 339.09 74.93 0)
			(effects
				(font
					(size 1.27 1.27)
					(thickness 0.15)
				)
				(justify left bottom)
				(hide yes)
			)
		)
		(property "Description" ""
			(at 314.96 67.31 0)
			(effects
				(font
					(size 1.27 1.27)
				)
				(hide yes)
			)
		)
		(property "Manufacturer" "Texas Instruments"
			(at 339.09 80.01 0)
			(effects
				(font
					(size 1.27 1.27)
					(thickness 0.15)
				)
				(justify left bottom)
				(hide yes)
			)
		)
		(property "MPN" "TPD4E05U06QDQARQ1"
			(at 325.12 73.025 0)
			(effects
				(font
					(size 1.27 1.27)
					(thickness 0.15)
				)
				(justify left)
			)
		)
		(property "Author" "Antmicro"
			(at 339.09 82.55 0)
			(effects
				(font
					(size 1.27 1.27)
					(thickness 0.15)
				)
				(justify left bottom)
				(hide yes)
			)
		)
		(property "License" "Apache-2.0"
			(at 339.09 85.09 0)
			(effects
				(font
					(size 1.27 1.27)
					(thickness 0.15)
				)
				(justify left bottom)
				(hide yes)
			)
		)
		(pin "1"
		)
		(pin "10"
		)
		(pin "2"
		)
		(pin "3"
		)
		(pin "4"
		)
		(pin "5"
		)
		(pin "6"
		)
		(pin "7"
		)
		(pin "8"
		)
		(pin "9"
		)
		(instances
			(project "jetson-orin-baseboard"
				(path ""
					(reference "U45")
					(unit 1)
				)
			)
		)
	)
	(symbol
		(lib_id "antmicroResistors0402:R_2k2_0402")
		(at 256.54 179.07 90)
		(unit 1)
		(exclude_from_sim no)
		(in_bom no)
		(on_board yes)
		(dnp yes)
		(property "Reference" "R279"
			(at 255.27 175.26 90)
			(effects
				(font
					(size 1.27 1.27)
				)
				(justify left)
			)
		)
		(property "Value" "R_2k2_0402"
			(at 269.24 158.75 0)
			(effects
				(font
					(size 1.27 1.27)
					(thickness 0.15)
				)
				(justify left bottom)
				(hide yes)
			)
		)
		(property "Footprint" "antmicro-footprints:R_0402_1005Metric"
			(at 271.78 158.75 0)
			(effects
				(font
					(size 1.27 1.27)
					(thickness 0.15)
				)
				(justify left bottom)
				(hide yes)
			)
		)
		(property "Datasheet" "https://www.bourns.com/docs/product-datasheets/cr.pdf"
			(at 274.32 158.75 0)
			(effects
				(font
					(size 1.27 1.27)
					(thickness 0.15)
				)
				(justify left bottom)
				(hide yes)
			)
		)
		(property "Description" ""
			(at 256.54 179.07 0)
			(effects
				(font
					(size 1.27 1.27)
				)
				(hide yes)
			)
		)
		(property "Manufacturer" "Bourns"
			(at 279.4 158.75 0)
			(effects
				(font
					(size 1.27 1.27)
					(thickness 0.15)
				)
				(justify left bottom)
				(hide yes)
			)
		)
		(property "MPN" "CR0402-FX-2201GLF"
			(at 276.86 158.75 0)
			(effects
				(font
					(size 1.27 1.27)
					(thickness 0.15)
				)
				(justify left bottom)
				(hide yes)
			)
		)
		(property "Val" "2k2"
			(at 255.27 177.8 90)
			(effects
				(font
					(size 1.27 1.27)
					(thickness 0.15)
				)
				(justify left)
			)
		)
		(property "License" "Apache-2.0"
			(at 281.94 158.75 0)
			(effects
				(font
					(size 1.27 1.27)
					(thickness 0.15)
				)
				(justify left bottom)
				(hide yes)
			)
		)
		(property "Author" "Antmicro"
			(at 284.48 158.75 0)
			(effects
				(font
					(size 1.27 1.27)
					(thickness 0.15)
				)
				(justify left bottom)
				(hide yes)
			)
		)
		(property "Tolerance" "1%"
			(at 266.7 158.75 0)
			(effects
				(font
					(size 1.27 1.27)
				)
				(justify left bottom)
				(hide yes)
			)
		)
		(pin "1"
		)
		(pin "2"
		)
		(instances
			(project "jetson-orin-baseboard"
				(path ""
					(reference "R279")
					(unit 1)
				)
			)
		)
	)
	(symbol
		(lib_id "antmicroResistors0402:R_0R_0402")
		(at 40.64 165.1 180)
		(unit 1)
		(exclude_from_sim no)
		(in_bom yes)
		(on_board yes)
		(dnp no)
		(property "Reference" "R40"
			(at 44.45 163.195 0)
			(effects
				(font
					(size 1.27 1.27)
				)
				(justify left bottom)
			)
		)
		(property "Value" "R_0R_0402"
			(at 20.32 152.4 0)
			(effects
				(font
					(size 1.27 1.27)
					(thickness 0.15)
				)
				(justify left bottom)
				(hide yes)
			)
		)
		(property "Footprint" "antmicro-footprints:R_0402_1005Metric"
			(at 20.32 149.86 0)
			(effects
				(font
					(size 1.27 1.27)
					(thickness 0.15)
				)
				(justify left bottom)
				(hide yes)
			)
		)
		(property "Datasheet" "https://industrial.panasonic.com/cdbs/www-data/pdf/RDA0000/AOA0000C301.pdf"
			(at 20.32 147.32 0)
			(effects
				(font
					(size 1.27 1.27)
					(thickness 0.15)
				)
				(justify left bottom)
				(hide yes)
			)
		)
		(property "Description" ""
			(at 40.64 165.1 0)
			(effects
				(font
					(size 1.27 1.27)
				)
				(hide yes)
			)
		)
		(property "Manufacturer" "Panasonic"
			(at 20.32 142.24 0)
			(effects
				(font
					(size 1.27 1.27)
					(thickness 0.15)
				)
				(justify left bottom)
				(hide yes)
			)
		)
		(property "MPN" "ERJ2GE0R00X"
			(at 20.32 144.78 0)
			(effects
				(font
					(size 1.27 1.27)
					(thickness 0.15)
				)
				(justify left bottom)
				(hide yes)
			)
		)
		(property "Val" "0R"
			(at 35.56 163.195 0)
			(effects
				(font
					(size 1.27 1.27)
					(thickness 0.15)
				)
				(justify left bottom)
			)
		)
		(property "License" "Apache-2.0"
			(at 20.32 139.7 0)
			(effects
				(font
					(size 1.27 1.27)
					(thickness 0.15)
				)
				(justify left bottom)
				(hide yes)
			)
		)
		(property "Author" "Antmicro"
			(at 20.32 137.16 0)
			(effects
				(font
					(size 1.27 1.27)
					(thickness 0.15)
				)
				(justify left bottom)
				(hide yes)
			)
		)
		(property "Tolerance" "~"
			(at 20.32 154.94 0)
			(effects
				(font
					(size 1.27 1.27)
				)
				(justify left bottom)
				(hide yes)
			)
		)
		(property "Current" "1A"
			(at 20.32 134.62 0)
			(effects
				(font
					(size 1.27 1.27)
					(thickness 0.15)
				)
				(justify left bottom)
				(hide yes)
			)
		)
		(pin "1"
		)
		(pin "2"
		)
		(instances
			(project "jetson-orin-baseboard"
				(path ""
					(reference "R40")
					(unit 1)
				)
			)
		)
	)
	(symbol
		(lib_id "antmicroVideoConnectors:HDMI-Mini-C_WE_685119136923")
		(at 358.14 137.16 0)
		(unit 1)
		(exclude_from_sim no)
		(in_bom yes)
		(on_board yes)
		(dnp no)
		(property "Reference" "J13"
			(at 370.84 130.81 0)
			(effects
				(font
					(size 1.27 1.27)
					(thickness 0.15)
				)
			)
		)
		(property "Value" "HDMI-Mini-C_WE_685119136923"
			(at 417.83 142.24 0)
			(effects
				(font
					(size 1.27 1.27)
					(thickness 0.15)
				)
				(justify left bottom)
				(hide yes)
			)
		)
		(property "Footprint" "antmicro-footprints:HDMI-Mini-C_Receptacle_WE_685119136923"
			(at 417.83 144.78 0)
			(effects
				(font
					(size 1.27 1.27)
					(thickness 0.15)
				)
				(justify left bottom)
				(hide yes)
			)
		)
		(property "Datasheet" "https://www.we-online.com/components/products/datasheet/685119136923.pdf"
			(at 417.83 147.32 0)
			(effects
				(font
					(size 1.27 1.27)
					(thickness 0.15)
				)
				(justify left bottom)
				(hide yes)
			)
		)
		(property "Description" ""
			(at 358.14 137.16 0)
			(effects
				(font
					(size 1.27 1.27)
				)
				(hide yes)
			)
		)
		(property "Manufacturer" "Würth Elektronik"
			(at 417.83 149.86 0)
			(effects
				(font
					(size 1.27 1.27)
					(thickness 0.15)
				)
				(justify left bottom)
				(hide yes)
			)
		)
		(property "MPN" "685119136923"
			(at 370.84 133.35 0)
			(effects
				(font
					(size 1.27 1.27)
					(thickness 0.15)
				)
			)
		)
		(property "Author" "Antmicro"
			(at 417.83 154.94 0)
			(effects
				(font
					(size 1.27 1.27)
					(thickness 0.15)
				)
				(justify left bottom)
				(hide yes)
			)
		)
		(property "License" "Apache-2.0"
			(at 417.83 157.48 0)
			(effects
				(font
					(size 1.27 1.27)
					(thickness 0.15)
				)
				(justify left bottom)
				(hide yes)
			)
		)
		(pin "1"
		)
		(pin "10"
		)
		(pin "11"
		)
		(pin "12"
		)
		(pin "13"
		)
		(pin "14"
		)
		(pin "15"
		)
		(pin "16"
		)
		(pin "17"
		)
		(pin "18"
		)
		(pin "19"
		)
		(pin "2"
		)
		(pin "3"
		)
		(pin "4"
		)
		(pin "5"
		)
		(pin "6"
		)
		(pin "7"
		)
		(pin "8"
		)
		(pin "9"
		)
		(pin "SH"
		)
		(instances
			(project "jetson-orin-baseboard"
				(path ""
					(reference "J13")
					(unit 1)
				)
			)
		)
	)
	(symbol
		(lib_id "antmicropower:GND")
		(at 97.79 179.07 0)
		(unit 1)
		(exclude_from_sim no)
		(in_bom yes)
		(on_board yes)
		(dnp no)
		(property "Reference" "#PWR055"
			(at 97.79 185.42 0)
			(effects
				(font
					(size 1.27 1.27)
				)
				(justify left bottom)
				(hide yes)
			)
		)
		(property "Value" "GND"
			(at 97.79 182.88 0)
			(effects
				(font
					(size 1.27 1.27)
					(thickness 0.15)
				)
			)
		)
		(property "Footprint" ""
			(at 106.68 186.69 0)
			(effects
				(font
					(size 1.27 1.27)
					(thickness 0.15)
				)
				(justify left bottom)
				(hide yes)
			)
		)
		(property "Datasheet" ""
			(at 106.68 191.77 0)
			(effects
				(font
					(size 1.27 1.27)
					(thickness 0.15)
				)
				(justify left bottom)
				(hide yes)
			)
		)
		(property "Description" ""
			(at 97.79 179.07 0)
			(effects
				(font
					(size 1.27 1.27)
				)
				(hide yes)
			)
		)
		(property "Author" "Antmicro"
			(at 106.68 186.69 0)
			(effects
				(font
					(size 1.27 1.27)
					(thickness 0.15)
				)
				(justify left bottom)
				(hide yes)
			)
		)
		(property "License" "Apache-2.0"
			(at 106.68 189.23 0)
			(effects
				(font
					(size 1.27 1.27)
					(thickness 0.15)
				)
				(justify left bottom)
				(hide yes)
			)
		)
		(pin "1"
		)
		(instances
			(project "jetson-orin-baseboard"
				(path ""
					(reference "#PWR055")
					(unit 1)
				)
			)
		)
	)
	(symbol
		(lib_id "antmicropower:GND")
		(at 313.69 102.87 0)
		(unit 1)
		(exclude_from_sim no)
		(in_bom yes)
		(on_board yes)
		(dnp no)
		(property "Reference" "#PWR0284"
			(at 313.69 109.22 0)
			(effects
				(font
					(size 1.27 1.27)
				)
				(justify left bottom)
				(hide yes)
			)
		)
		(property "Value" "GND"
			(at 313.69 106.68 0)
			(effects
				(font
					(size 1.27 1.27)
					(thickness 0.15)
				)
			)
		)
		(property "Footprint" ""
			(at 322.58 110.49 0)
			(effects
				(font
					(size 1.27 1.27)
					(thickness 0.15)
				)
				(justify left bottom)
				(hide yes)
			)
		)
		(property "Datasheet" ""
			(at 322.58 115.57 0)
			(effects
				(font
					(size 1.27 1.27)
					(thickness 0.15)
				)
				(justify left bottom)
				(hide yes)
			)
		)
		(property "Description" ""
			(at 313.69 102.87 0)
			(effects
				(font
					(size 1.27 1.27)
				)
				(hide yes)
			)
		)
		(property "Author" "Antmicro"
			(at 322.58 110.49 0)
			(effects
				(font
					(size 1.27 1.27)
					(thickness 0.15)
				)
				(justify left bottom)
				(hide yes)
			)
		)
		(property "License" "Apache-2.0"
			(at 322.58 113.03 0)
			(effects
				(font
					(size 1.27 1.27)
					(thickness 0.15)
				)
				(justify left bottom)
				(hide yes)
			)
		)
		(pin "1"
		)
		(instances
			(project "jetson-orin-baseboard"
				(path ""
					(reference "#PWR0284")
					(unit 1)
				)
			)
		)
	)
	(symbol
		(lib_id "antmicropower:+3V3")
		(at 260.35 190.5 0)
		(unit 1)
		(exclude_from_sim no)
		(in_bom yes)
		(on_board yes)
		(dnp no)
		(property "Reference" "#PWR0295"
			(at 260.35 194.31 0)
			(effects
				(font
					(size 1.27 1.27)
				)
				(justify left bottom)
				(hide yes)
			)
		)
		(property "Value" "+3V3"
			(at 257.175 187.325 0)
			(effects
				(font
					(size 1.27 1.27)
					(thickness 0.15)
				)
				(justify left bottom)
			)
		)
		(property "Footprint" ""
			(at 275.59 198.12 0)
			(effects
				(font
					(size 1.27 1.27)
					(thickness 0.15)
				)
				(justify left bottom)
				(hide yes)
			)
		)
		(property "Datasheet" ""
			(at 275.59 200.66 0)
			(effects
				(font
					(size 1.27 1.27)
					(thickness 0.15)
				)
				(justify left bottom)
				(hide yes)
			)
		)
		(property "Description" ""
			(at 260.35 190.5 0)
			(effects
				(font
					(size 1.27 1.27)
				)
				(hide yes)
			)
		)
		(property "Author" "Antmicro"
			(at 275.59 193.04 0)
			(effects
				(font
					(size 1.27 1.27)
					(thickness 0.15)
				)
				(justify left bottom)
				(hide yes)
			)
		)
		(property "License" "Apache-2.0"
			(at 275.59 195.58 0)
			(effects
				(font
					(size 1.27 1.27)
					(thickness 0.15)
				)
				(justify left bottom)
				(hide yes)
			)
		)
		(pin "1"
		)
		(instances
			(project "jetson-orin-baseboard"
				(path ""
					(reference "#PWR0295")
					(unit 1)
				)
			)
		)
	)
	(symbol
		(lib_id "antmicroResistors0402:R_2k2_0402")
		(at 269.24 213.36 90)
		(unit 1)
		(exclude_from_sim no)
		(in_bom no)
		(on_board yes)
		(dnp yes)
		(property "Reference" "R208"
			(at 270.51 209.55 90)
			(effects
				(font
					(size 1.27 1.27)
				)
				(justify right)
			)
		)
		(property "Value" "R_2k2_0402"
			(at 281.94 193.04 0)
			(effects
				(font
					(size 1.27 1.27)
					(thickness 0.15)
				)
				(justify left bottom)
				(hide yes)
			)
		)
		(property "Footprint" "antmicro-footprints:R_0402_1005Metric"
			(at 284.48 193.04 0)
			(effects
				(font
					(size 1.27 1.27)
					(thickness 0.15)
				)
				(justify left bottom)
				(hide yes)
			)
		)
		(property "Datasheet" "https://www.bourns.com/docs/product-datasheets/cr.pdf"
			(at 287.02 193.04 0)
			(effects
				(font
					(size 1.27 1.27)
					(thickness 0.15)
				)
				(justify left bottom)
				(hide yes)
			)
		)
		(property "Description" ""
			(at 269.24 213.36 0)
			(effects
				(font
					(size 1.27 1.27)
				)
				(hide yes)
			)
		)
		(property "Manufacturer" "Bourns"
			(at 292.1 193.04 0)
			(effects
				(font
					(size 1.27 1.27)
					(thickness 0.15)
				)
				(justify left bottom)
				(hide yes)
			)
		)
		(property "MPN" "CR0402-FX-2201GLF"
			(at 289.56 193.04 0)
			(effects
				(font
					(size 1.27 1.27)
					(thickness 0.15)
				)
				(justify left bottom)
				(hide yes)
			)
		)
		(property "Val" "2k2"
			(at 270.51 212.09 90)
			(effects
				(font
					(size 1.27 1.27)
					(thickness 0.15)
				)
				(justify right)
			)
		)
		(property "License" "Apache-2.0"
			(at 294.64 193.04 0)
			(effects
				(font
					(size 1.27 1.27)
					(thickness 0.15)
				)
				(justify left bottom)
				(hide yes)
			)
		)
		(property "Author" "Antmicro"
			(at 297.18 193.04 0)
			(effects
				(font
					(size 1.27 1.27)
					(thickness 0.15)
				)
				(justify left bottom)
				(hide yes)
			)
		)
		(property "Tolerance" "1%"
			(at 279.4 193.04 0)
			(effects
				(font
					(size 1.27 1.27)
				)
				(justify left bottom)
				(hide yes)
			)
		)
		(pin "1"
		)
		(pin "2"
		)
		(instances
			(project "jetson-orin-baseboard"
				(path ""
					(reference "R208")
					(unit 1)
				)
			)
		)
	)
	(symbol
		(lib_id "antmicroCapacitors0402:C_1u_0402")
		(at 76.2 86.36 90)
		(unit 1)
		(exclude_from_sim no)
		(in_bom yes)
		(on_board yes)
		(dnp no)
		(property "Reference" "C47"
			(at 78.105 82.55 90)
			(effects
				(font
					(size 1.27 1.27)
				)
				(justify right)
			)
		)
		(property "Value" "C_1u_0402"
			(at 86.36 66.04 0)
			(effects
				(font
					(size 1.27 1.27)
					(thickness 0.15)
				)
				(justify left bottom)
				(hide yes)
			)
		)
		(property "Footprint" "antmicro-footprints:C_0402_1005Metric"
			(at 88.9 66.04 0)
			(effects
				(font
					(size 1.27 1.27)
					(thickness 0.15)
				)
				(justify left bottom)
				(hide yes)
			)
		)
		(property "Datasheet" "https://product.tdk.com/en/search/capacitor/ceramic/mlcc/info?part_no=C1005X6S1A105K050BC"
			(at 91.44 66.04 0)
			(effects
				(font
					(size 1.27 1.27)
					(thickness 0.15)
				)
				(justify left bottom)
				(hide yes)
			)
		)
		(property "Description" ""
			(at 76.2 86.36 0)
			(effects
				(font
					(size 1.27 1.27)
				)
				(hide yes)
			)
		)
		(property "Manufacturer" "TDK"
			(at 96.52 66.04 0)
			(effects
				(font
					(size 1.27 1.27)
					(thickness 0.15)
				)
				(justify left bottom)
				(hide yes)
			)
		)
		(property "MPN" "C1005X6S1A105K050BC"
			(at 93.98 66.04 0)
			(effects
				(font
					(size 1.27 1.27)
					(thickness 0.15)
				)
				(justify left bottom)
				(hide yes)
			)
		)
		(property "Val" "1u"
			(at 78.105 85.09 90)
			(effects
				(font
					(size 1.27 1.27)
					(thickness 0.15)
				)
				(justify right)
			)
		)
		(property "License" "Apache-2.0"
			(at 99.06 66.04 0)
			(effects
				(font
					(size 1.27 1.27)
					(thickness 0.15)
				)
				(justify left bottom)
				(hide yes)
			)
		)
		(property "Author" "Antmicro"
			(at 101.6 66.04 0)
			(effects
				(font
					(size 1.27 1.27)
					(thickness 0.15)
				)
				(justify left bottom)
				(hide yes)
			)
		)
		(property "Voltage" ""
			(at 104.14 66.04 0)
			(effects
				(font
					(size 1.27 1.27)
				)
				(justify left bottom)
				(hide yes)
			)
		)
		(property "Dielectric" ""
			(at 106.68 66.04 0)
			(effects
				(font
					(size 1.27 1.27)
				)
				(justify left bottom)
				(hide yes)
			)
		)
		(pin "1"
		)
		(pin "2"
		)
		(instances
			(project "jetson-orin-baseboard"
				(path ""
					(reference "C47")
					(unit 1)
				)
			)
		)
	)
	(symbol
		(lib_id "antmicroCapacitors0402:C_100n_0402")
		(at 71.12 127 0)
		(mirror y)
		(unit 1)
		(exclude_from_sim no)
		(in_bom yes)
		(on_board yes)
		(dnp no)
		(property "Reference" "C133"
			(at 69.85 126.365 0)
			(effects
				(font
					(size 1.27 1.27)
				)
				(justify right bottom)
			)
		)
		(property "Value" "C_100n_0402"
			(at 50.8 137.16 0)
			(effects
				(font
					(size 1.27 1.27)
					(thickness 0.15)
				)
				(justify left bottom)
				(hide yes)
			)
		)
		(property "Footprint" "antmicro-footprints:C_0402_1005Metric"
			(at 50.8 139.7 0)
			(effects
				(font
					(size 1.27 1.27)
					(thickness 0.15)
				)
				(justify left bottom)
				(hide yes)
			)
		)
		(property "Datasheet" "https://www.murata.com/products/productdetail?partno=GRM155R61H104KE14%23"
			(at 50.8 142.24 0)
			(effects
				(font
					(size 1.27 1.27)
					(thickness 0.15)
				)
				(justify left bottom)
				(hide yes)
			)
		)
		(property "Description" ""
			(at 71.12 127 0)
			(effects
				(font
					(size 1.27 1.27)
				)
				(hide yes)
			)
		)
		(property "Manufacturer" "Murata"
			(at 50.8 147.32 0)
			(effects
				(font
					(size 1.27 1.27)
					(thickness 0.15)
				)
				(justify left bottom)
				(hide yes)
			)
		)
		(property "MPN" "GRM155R61H104KE14D"
			(at 50.8 144.78 0)
			(effects
				(font
					(size 1.27 1.27)
					(thickness 0.15)
				)
				(justify left bottom)
				(hide yes)
			)
		)
		(property "Val" "100n"
			(at 67.31 128.905 0)
			(effects
				(font
					(size 1.27 1.27)
					(thickness 0.15)
				)
				(justify left bottom)
			)
		)
		(property "License" "Apache-2.0"
			(at 50.8 149.86 0)
			(effects
				(font
					(size 1.27 1.27)
					(thickness 0.15)
				)
				(justify left bottom)
				(hide yes)
			)
		)
		(property "Author" "Antmicro"
			(at 50.8 152.4 0)
			(effects
				(font
					(size 1.27 1.27)
					(thickness 0.15)
				)
				(justify left bottom)
				(hide yes)
			)
		)
		(property "Voltage" "50V"
			(at 50.8 154.94 0)
			(effects
				(font
					(size 1.27 1.27)
				)
				(justify left bottom)
				(hide yes)
			)
		)
		(property "Dielectric" "X5R"
			(at 50.8 157.48 0)
			(effects
				(font
					(size 1.27 1.27)
				)
				(justify left bottom)
				(hide yes)
			)
		)
		(pin "1"
		)
		(pin "2"
		)
		(instances
			(project "jetson-orin-baseboard"
				(path ""
					(reference "C133")
					(unit 1)
				)
			)
		)
	)
	(symbol
		(lib_id "antmicroResistors0402:R_0R_0402")
		(at 212.09 168.91 0)
		(unit 1)
		(exclude_from_sim no)
		(in_bom yes)
		(on_board yes)
		(dnp no)
		(property "Reference" "R278"
			(at 217.17 168.275 0)
			(effects
				(font
					(size 1.27 1.27)
				)
				(justify left bottom)
			)
		)
		(property "Value" "R_0R_0402"
			(at 232.41 181.61 0)
			(effects
				(font
					(size 1.27 1.27)
					(thickness 0.15)
				)
				(justify left bottom)
				(hide yes)
			)
		)
		(property "Footprint" "antmicro-footprints:R_0402_1005Metric"
			(at 232.41 184.15 0)
			(effects
				(font
					(size 1.27 1.27)
					(thickness 0.15)
				)
				(justify left bottom)
				(hide yes)
			)
		)
		(property "Datasheet" "https://industrial.panasonic.com/cdbs/www-data/pdf/RDA0000/AOA0000C301.pdf"
			(at 232.41 186.69 0)
			(effects
				(font
					(size 1.27 1.27)
					(thickness 0.15)
				)
				(justify left bottom)
				(hide yes)
			)
		)
		(property "Description" ""
			(at 212.09 168.91 0)
			(effects
				(font
					(size 1.27 1.27)
				)
				(hide yes)
			)
		)
		(property "Manufacturer" "Panasonic"
			(at 232.41 191.77 0)
			(effects
				(font
					(size 1.27 1.27)
					(thickness 0.15)
				)
				(justify left bottom)
				(hide yes)
			)
		)
		(property "MPN" "ERJ2GE0R00X"
			(at 232.41 189.23 0)
			(effects
				(font
					(size 1.27 1.27)
					(thickness 0.15)
				)
				(justify left bottom)
				(hide yes)
			)
		)
		(property "Val" "0R"
			(at 209.55 168.275 0)
			(effects
				(font
					(size 1.27 1.27)
					(thickness 0.15)
				)
				(justify left bottom)
			)
		)
		(property "License" "Apache-2.0"
			(at 232.41 194.31 0)
			(effects
				(font
					(size 1.27 1.27)
					(thickness 0.15)
				)
				(justify left bottom)
				(hide yes)
			)
		)
		(property "Author" "Antmicro"
			(at 232.41 196.85 0)
			(effects
				(font
					(size 1.27 1.27)
					(thickness 0.15)
				)
				(justify left bottom)
				(hide yes)
			)
		)
		(property "Tolerance" "~"
			(at 232.41 179.07 0)
			(effects
				(font
					(size 1.27 1.27)
				)
				(justify left bottom)
				(hide yes)
			)
		)
		(property "Current" "1A"
			(at 232.41 199.39 0)
			(effects
				(font
					(size 1.27 1.27)
					(thickness 0.15)
				)
				(justify left bottom)
				(hide yes)
			)
		)
		(pin "1"
		)
		(pin "2"
		)
		(instances
			(project "jetson-orin-baseboard"
				(path ""
					(reference "R278")
					(unit 1)
				)
			)
		)
	)
	(symbol
		(lib_id "antmicroCapacitors0402:C_100n_0402")
		(at 74.93 139.7 0)
		(mirror y)
		(unit 1)
		(exclude_from_sim no)
		(in_bom yes)
		(on_board yes)
		(dnp no)
		(property "Reference" "C92"
			(at 73.66 139.065 0)
			(effects
				(font
					(size 1.27 1.27)
				)
				(justify right bottom)
			)
		)
		(property "Value" "C_100n_0402"
			(at 54.61 149.86 0)
			(effects
				(font
					(size 1.27 1.27)
					(thickness 0.15)
				)
				(justify left bottom)
				(hide yes)
			)
		)
		(property "Footprint" "antmicro-footprints:C_0402_1005Metric"
			(at 54.61 152.4 0)
			(effects
				(font
					(size 1.27 1.27)
					(thickness 0.15)
				)
				(justify left bottom)
				(hide yes)
			)
		)
		(property "Datasheet" "https://www.murata.com/products/productdetail?partno=GRM155R61H104KE14%23"
			(at 54.61 154.94 0)
			(effects
				(font
					(size 1.27 1.27)
					(thickness 0.15)
				)
				(justify left bottom)
				(hide yes)
			)
		)
		(property "Description" ""
			(at 74.93 139.7 0)
			(effects
				(font
					(size 1.27 1.27)
				)
				(hide yes)
			)
		)
		(property "Manufacturer" "Murata"
			(at 54.61 160.02 0)
			(effects
				(font
					(size 1.27 1.27)
					(thickness 0.15)
				)
				(justify left bottom)
				(hide yes)
			)
		)
		(property "MPN" "GRM155R61H104KE14D"
			(at 54.61 157.48 0)
			(effects
				(font
					(size 1.27 1.27)
					(thickness 0.15)
				)
				(justify left bottom)
				(hide yes)
			)
		)
		(property "Val" "100n"
			(at 71.12 141.605 0)
			(effects
				(font
					(size 1.27 1.27)
					(thickness 0.15)
				)
				(justify left bottom)
			)
		)
		(property "License" "Apache-2.0"
			(at 54.61 162.56 0)
			(effects
				(font
					(size 1.27 1.27)
					(thickness 0.15)
				)
				(justify left bottom)
				(hide yes)
			)
		)
		(property "Author" "Antmicro"
			(at 54.61 165.1 0)
			(effects
				(font
					(size 1.27 1.27)
					(thickness 0.15)
				)
				(justify left bottom)
				(hide yes)
			)
		)
		(property "Voltage" "50V"
			(at 54.61 167.64 0)
			(effects
				(font
					(size 1.27 1.27)
				)
				(justify left bottom)
				(hide yes)
			)
		)
		(property "Dielectric" "X5R"
			(at 54.61 170.18 0)
			(effects
				(font
					(size 1.27 1.27)
				)
				(justify left bottom)
				(hide yes)
			)
		)
		(pin "1"
		)
		(pin "2"
		)
		(instances
			(project "jetson-orin-baseboard"
				(path ""
					(reference "C92")
					(unit 1)
				)
			)
		)
	)
	(symbol
		(lib_id "antmicroResistors0402:R_0R_0402")
		(at 295.91 215.9 0)
		(unit 1)
		(exclude_from_sim no)
		(in_bom yes)
		(on_board yes)
		(dnp no)
		(property "Reference" "R226"
			(at 300.99 215.265 0)
			(effects
				(font
					(size 1.27 1.27)
				)
				(justify left bottom)
			)
		)
		(property "Value" "R_0R_0402"
			(at 316.23 228.6 0)
			(effects
				(font
					(size 1.27 1.27)
					(thickness 0.15)
				)
				(justify left bottom)
				(hide yes)
			)
		)
		(property "Footprint" "antmicro-footprints:R_0402_1005Metric"
			(at 316.23 231.14 0)
			(effects
				(font
					(size 1.27 1.27)
					(thickness 0.15)
				)
				(justify left bottom)
				(hide yes)
			)
		)
		(property "Datasheet" "https://industrial.panasonic.com/cdbs/www-data/pdf/RDA0000/AOA0000C301.pdf"
			(at 316.23 233.68 0)
			(effects
				(font
					(size 1.27 1.27)
					(thickness 0.15)
				)
				(justify left bottom)
				(hide yes)
			)
		)
		(property "Description" ""
			(at 295.91 215.9 0)
			(effects
				(font
					(size 1.27 1.27)
				)
				(hide yes)
			)
		)
		(property "Manufacturer" "Panasonic"
			(at 316.23 238.76 0)
			(effects
				(font
					(size 1.27 1.27)
					(thickness 0.15)
				)
				(justify left bottom)
				(hide yes)
			)
		)
		(property "MPN" "ERJ2GE0R00X"
			(at 316.23 236.22 0)
			(effects
				(font
					(size 1.27 1.27)
					(thickness 0.15)
				)
				(justify left bottom)
				(hide yes)
			)
		)
		(property "Val" "0R"
			(at 293.37 215.265 0)
			(effects
				(font
					(size 1.27 1.27)
					(thickness 0.15)
				)
				(justify left bottom)
			)
		)
		(property "License" "Apache-2.0"
			(at 316.23 241.3 0)
			(effects
				(font
					(size 1.27 1.27)
					(thickness 0.15)
				)
				(justify left bottom)
				(hide yes)
			)
		)
		(property "Author" "Antmicro"
			(at 316.23 243.84 0)
			(effects
				(font
					(size 1.27 1.27)
					(thickness 0.15)
				)
				(justify left bottom)
				(hide yes)
			)
		)
		(property "Tolerance" "~"
			(at 316.23 226.06 0)
			(effects
				(font
					(size 1.27 1.27)
				)
				(justify left bottom)
				(hide yes)
			)
		)
		(property "Current" "1A"
			(at 316.23 246.38 0)
			(effects
				(font
					(size 1.27 1.27)
					(thickness 0.15)
				)
				(justify left bottom)
				(hide yes)
			)
		)
		(pin "1"
		)
		(pin "2"
		)
		(instances
			(project "jetson-orin-baseboard"
				(path ""
					(reference "R226")
					(unit 1)
				)
			)
		)
	)
	(symbol
		(lib_id "antmicroTestPoints:TP_0.75mm_SMD")
		(at 243.84 181.61 180)
		(unit 1)
		(exclude_from_sim no)
		(in_bom no)
		(on_board yes)
		(dnp no)
		(property "Reference" "TP56"
			(at 240.03 181.61 0)
			(effects
				(font
					(size 1.27 1.27)
				)
				(justify left)
			)
		)
		(property "Value" "TP_0.75mm_SMD"
			(at 233.68 177.8 0)
			(effects
				(font
					(size 1.27 1.27)
					(thickness 0.15)
				)
				(justify left bottom)
				(hide yes)
			)
		)
		(property "Footprint" "antmicro-footprints:TP_SMD_0.75mm"
			(at 233.68 175.26 0)
			(effects
				(font
					(size 1.27 1.27)
					(thickness 0.15)
				)
				(justify left bottom)
				(hide yes)
			)
		)
		(property "Datasheet" ""
			(at 226.06 168.91 0)
			(effects
				(font
					(size 1.27 1.27)
					(thickness 0.15)
				)
				(justify left bottom)
				(hide yes)
			)
		)
		(property "Description" ""
			(at 243.84 181.61 0)
			(effects
				(font
					(size 1.27 1.27)
				)
				(hide yes)
			)
		)
		(property "MPN" ""
			(at 233.045 170.18 0)
			(effects
				(font
					(size 1.27 1.27)
					(thickness 0.15)
				)
				(justify left bottom)
				(hide yes)
			)
		)
		(property "Manufacturer" ""
			(at 233.045 175.26 0)
			(effects
				(font
					(size 1.27 1.27)
					(thickness 0.15)
				)
				(justify left bottom)
				(hide yes)
			)
		)
		(property "Author" "Antmicro"
			(at 233.68 172.72 0)
			(effects
				(font
					(size 1.27 1.27)
					(thickness 0.15)
				)
				(justify left bottom)
				(hide yes)
			)
		)
		(property "License" "Apache-2.0"
			(at 233.68 170.18 0)
			(effects
				(font
					(size 1.27 1.27)
					(thickness 0.15)
				)
				(justify left bottom)
				(hide yes)
			)
		)
		(pin "1"
		)
		(instances
			(project "jetson-orin-baseboard"
				(path ""
					(reference "TP56")
					(unit 1)
				)
			)
		)
	)
	(symbol
		(lib_id "antmicroTVSDiodes:TPD4E05U06QDQARQ1")
		(at 314.96 91.44 0)
		(unit 1)
		(exclude_from_sim no)
		(in_bom yes)
		(on_board yes)
		(dnp no)
		(fields_autoplaced yes)
		(property "Reference" "U46"
			(at 325.12 94.615 0)
			(effects
				(font
					(size 1.27 1.27)
				)
				(justify left)
			)
		)
		(property "Value" "TPD4E05U06QDQARQ1"
			(at 339.09 101.6 0)
			(effects
				(font
					(size 1.27 1.27)
					(thickness 0.15)
				)
				(justify left bottom)
				(hide yes)
			)
		)
		(property "Footprint" "antmicro-footprints:USON-10_2.5x1mm_P0.5mm"
			(at 339.09 96.52 0)
			(effects
				(font
					(size 1.27 1.27)
					(thickness 0.15)
				)
				(justify left bottom)
				(hide yes)
			)
		)
		(property "Datasheet" "https://www.ti.com/lit/ds/symlink/tpd4e05u06-q1.pdf?HQS=dis-mous-null-mousermode-dsf-pf-null-wwe&ts=1663591265741&ref_url=https%253A%252F%252Fwww.mouser.com%252F"
			(at 339.09 99.06 0)
			(effects
				(font
					(size 1.27 1.27)
					(thickness 0.15)
				)
				(justify left bottom)
				(hide yes)
			)
		)
		(property "Description" ""
			(at 314.96 91.44 0)
			(effects
				(font
					(size 1.27 1.27)
				)
				(hide yes)
			)
		)
		(property "Manufacturer" "Texas Instruments"
			(at 339.09 104.14 0)
			(effects
				(font
					(size 1.27 1.27)
					(thickness 0.15)
				)
				(justify left bottom)
				(hide yes)
			)
		)
		(property "MPN" "TPD4E05U06QDQARQ1"
			(at 325.12 97.155 0)
			(effects
				(font
					(size 1.27 1.27)
					(thickness 0.15)
				)
				(justify left)
			)
		)
		(property "Author" "Antmicro"
			(at 339.09 106.68 0)
			(effects
				(font
					(size 1.27 1.27)
					(thickness 0.15)
				)
				(justify left bottom)
				(hide yes)
			)
		)
		(property "License" "Apache-2.0"
			(at 339.09 109.22 0)
			(effects
				(font
					(size 1.27 1.27)
					(thickness 0.15)
				)
				(justify left bottom)
				(hide yes)
			)
		)
		(pin "1"
		)
		(pin "10"
		)
		(pin "2"
		)
		(pin "3"
		)
		(pin "4"
		)
		(pin "5"
		)
		(pin "6"
		)
		(pin "7"
		)
		(pin "8"
		)
		(pin "9"
		)
		(instances
			(project "jetson-orin-baseboard"
				(path ""
					(reference "U46")
					(unit 1)
				)
			)
		)
	)
	(symbol
		(lib_id "antmicroResistors0402:R_10k_0402")
		(at 46.99 162.56 90)
		(unit 1)
		(exclude_from_sim no)
		(in_bom yes)
		(on_board yes)
		(dnp no)
		(property "Reference" "R47"
			(at 52.07 158.75 90)
			(effects
				(font
					(size 1.27 1.27)
				)
				(justify left)
			)
		)
		(property "Value" "R_10k_0402"
			(at 59.69 142.24 0)
			(effects
				(font
					(size 1.27 1.27)
					(thickness 0.15)
				)
				(justify left bottom)
				(hide yes)
			)
		)
		(property "Footprint" "antmicro-footprints:R_0402_1005Metric"
			(at 62.23 142.24 0)
			(effects
				(font
					(size 1.27 1.27)
					(thickness 0.15)
				)
				(justify left bottom)
				(hide yes)
			)
		)
		(property "Datasheet" "https://www.bourns.com/docs/product-datasheets/cr.pdf"
			(at 64.77 142.24 0)
			(effects
				(font
					(size 1.27 1.27)
					(thickness 0.15)
				)
				(justify left bottom)
				(hide yes)
			)
		)
		(property "Description" ""
			(at 46.99 162.56 0)
			(effects
				(font
					(size 1.27 1.27)
				)
				(hide yes)
			)
		)
		(property "Manufacturer" "Bourns"
			(at 69.85 142.24 0)
			(effects
				(font
					(size 1.27 1.27)
					(thickness 0.15)
				)
				(justify left bottom)
				(hide yes)
			)
		)
		(property "MPN" "CR0402-FX-1002GLF"
			(at 67.31 142.24 0)
			(effects
				(font
					(size 1.27 1.27)
					(thickness 0.15)
				)
				(justify left bottom)
				(hide yes)
			)
		)
		(property "Val" "10k"
			(at 52.07 161.29 90)
			(effects
				(font
					(size 1.27 1.27)
					(thickness 0.15)
				)
				(justify left)
			)
		)
		(property "License" "Apache-2.0"
			(at 72.39 142.24 0)
			(effects
				(font
					(size 1.27 1.27)
					(thickness 0.15)
				)
				(justify left bottom)
				(hide yes)
			)
		)
		(property "Author" "Antmicro"
			(at 74.93 142.24 0)
			(effects
				(font
					(size 1.27 1.27)
					(thickness 0.15)
				)
				(justify left bottom)
				(hide yes)
			)
		)
		(property "Tolerance" "1%"
			(at 57.15 142.24 0)
			(effects
				(font
					(size 1.27 1.27)
				)
				(justify left bottom)
				(hide yes)
			)
		)
		(pin "1"
		)
		(pin "2"
		)
		(instances
			(project "jetson-orin-baseboard"
				(path ""
					(reference "R47")
					(unit 1)
				)
			)
		)
	)
	(symbol
		(lib_id "antmicroCapacitors0402:C_100n_0402")
		(at 74.93 129.54 0)
		(mirror y)
		(unit 1)
		(exclude_from_sim no)
		(in_bom yes)
		(on_board yes)
		(dnp no)
		(property "Reference" "C88"
			(at 73.66 128.905 0)
			(effects
				(font
					(size 1.27 1.27)
				)
				(justify right bottom)
			)
		)
		(property "Value" "C_100n_0402"
			(at 54.61 139.7 0)
			(effects
				(font
					(size 1.27 1.27)
					(thickness 0.15)
				)
				(justify left bottom)
				(hide yes)
			)
		)
		(property "Footprint" "antmicro-footprints:C_0402_1005Metric"
			(at 54.61 142.24 0)
			(effects
				(font
					(size 1.27 1.27)
					(thickness 0.15)
				)
				(justify left bottom)
				(hide yes)
			)
		)
		(property "Datasheet" "https://www.murata.com/products/productdetail?partno=GRM155R61H104KE14%23"
			(at 54.61 144.78 0)
			(effects
				(font
					(size 1.27 1.27)
					(thickness 0.15)
				)
				(justify left bottom)
				(hide yes)
			)
		)
		(property "Description" ""
			(at 74.93 129.54 0)
			(effects
				(font
					(size 1.27 1.27)
				)
				(hide yes)
			)
		)
		(property "Manufacturer" "Murata"
			(at 54.61 149.86 0)
			(effects
				(font
					(size 1.27 1.27)
					(thickness 0.15)
				)
				(justify left bottom)
				(hide yes)
			)
		)
		(property "MPN" "GRM155R61H104KE14D"
			(at 54.61 147.32 0)
			(effects
				(font
					(size 1.27 1.27)
					(thickness 0.15)
				)
				(justify left bottom)
				(hide yes)
			)
		)
		(property "Val" "100n"
			(at 71.12 131.445 0)
			(effects
				(font
					(size 1.27 1.27)
					(thickness 0.15)
				)
				(justify left bottom)
			)
		)
		(property "License" "Apache-2.0"
			(at 54.61 152.4 0)
			(effects
				(font
					(size 1.27 1.27)
					(thickness 0.15)
				)
				(justify left bottom)
				(hide yes)
			)
		)
		(property "Author" "Antmicro"
			(at 54.61 154.94 0)
			(effects
				(font
					(size 1.27 1.27)
					(thickness 0.15)
				)
				(justify left bottom)
				(hide yes)
			)
		)
		(property "Voltage" "50V"
			(at 54.61 157.48 0)
			(effects
				(font
					(size 1.27 1.27)
				)
				(justify left bottom)
				(hide yes)
			)
		)
		(property "Dielectric" "X5R"
			(at 54.61 160.02 0)
			(effects
				(font
					(size 1.27 1.27)
				)
				(justify left bottom)
				(hide yes)
			)
		)
		(pin "1"
		)
		(pin "2"
		)
		(instances
			(project "jetson-orin-baseboard"
				(path ""
					(reference "C88")
					(unit 1)
				)
			)
		)
	)
	(symbol
		(lib_id "antmicroTransistorsFETsMOSFETsSingle:PJE138K")
		(at 275.59 224.79 0)
		(mirror y)
		(unit 1)
		(exclude_from_sim no)
		(in_bom no)
		(on_board yes)
		(dnp yes)
		(property "Reference" "Q12"
			(at 266.7 219.71 0)
			(effects
				(font
					(size 1.27 1.27)
					(thickness 0.15)
				)
				(justify left)
			)
		)
		(property "Value" "PJE138K"
			(at 252.73 233.68 0)
			(effects
				(font
					(size 1.27 1.27)
					(thickness 0.15)
				)
				(justify left bottom)
				(hide yes)
			)
		)
		(property "Footprint" "antmicro-footprints:SOT-523"
			(at 252.73 236.22 0)
			(effects
				(font
					(size 1.27 1.27)
					(thickness 0.15)
				)
				(justify left bottom)
				(hide yes)
			)
		)
		(property "Datasheet" "https://www.mouser.com/datasheet/2/1057/PJE138K-1876698.pdf"
			(at 252.73 238.76 0)
			(effects
				(font
					(size 1.27 1.27)
					(thickness 0.15)
				)
				(justify left bottom)
				(hide yes)
			)
		)
		(property "Description" ""
			(at 275.59 224.79 0)
			(effects
				(font
					(size 1.27 1.27)
				)
				(hide yes)
			)
		)
		(property "MPN" "PJE138K_R1_00001"
			(at 266.7 222.25 0)
			(effects
				(font
					(size 1.27 1.27)
					(thickness 0.15)
				)
				(justify left)
			)
		)
		(property "Manufacturer" "PANJIT"
			(at 252.73 243.84 0)
			(effects
				(font
					(size 1.27 1.27)
					(thickness 0.15)
				)
				(justify left bottom)
				(hide yes)
			)
		)
		(property "Author" "Antmicro"
			(at 252.73 246.38 0)
			(effects
				(font
					(size 1.27 1.27)
					(thickness 0.15)
				)
				(justify left bottom)
				(hide yes)
			)
		)
		(property "License" "Apache-2.0"
			(at 252.73 248.92 0)
			(effects
				(font
					(size 1.27 1.27)
					(thickness 0.15)
				)
				(justify left bottom)
				(hide yes)
			)
		)
		(pin "2"
		)
		(pin "3"
		)
		(pin "1"
		)
		(instances
			(project "jetson-orin-baseboard"
				(path ""
					(reference "Q12")
					(unit 1)
				)
			)
		)
	)
	(symbol
		(lib_id "antmicroTransistorsFETsMOSFETsSingle:PJE138K")
		(at 176.53 207.01 0)
		(unit 1)
		(exclude_from_sim no)
		(in_bom yes)
		(on_board yes)
		(dnp no)
		(property "Reference" "Q2"
			(at 185.42 203.2 0)
			(effects
				(font
					(size 1.27 1.27)
					(thickness 0.15)
				)
				(justify left)
			)
		)
		(property "Value" "PJE138K"
			(at 199.39 215.9 0)
			(effects
				(font
					(size 1.27 1.27)
					(thickness 0.15)
				)
				(justify left bottom)
				(hide yes)
			)
		)
		(property "Footprint" "antmicro-footprints:SOT-523"
			(at 199.39 218.44 0)
			(effects
				(font
					(size 1.27 1.27)
					(thickness 0.15)
				)
				(justify left bottom)
				(hide yes)
			)
		)
		(property "Datasheet" "https://www.mouser.com/datasheet/2/1057/PJE138K-1876698.pdf"
			(at 199.39 220.98 0)
			(effects
				(font
					(size 1.27 1.27)
					(thickness 0.15)
				)
				(justify left bottom)
				(hide yes)
			)
		)
		(property "Description" ""
			(at 176.53 207.01 0)
			(effects
				(font
					(size 1.27 1.27)
				)
				(hide yes)
			)
		)
		(property "MPN" "PJE138K_R1_00001"
			(at 185.42 205.74 0)
			(effects
				(font
					(size 1.27 1.27)
					(thickness 0.15)
				)
				(justify left)
			)
		)
		(property "Manufacturer" "PANJIT"
			(at 199.39 226.06 0)
			(effects
				(font
					(size 1.27 1.27)
					(thickness 0.15)
				)
				(justify left bottom)
				(hide yes)
			)
		)
		(property "Author" "Antmicro"
			(at 199.39 228.6 0)
			(effects
				(font
					(size 1.27 1.27)
					(thickness 0.15)
				)
				(justify left bottom)
				(hide yes)
			)
		)
		(property "License" "Apache-2.0"
			(at 199.39 231.14 0)
			(effects
				(font
					(size 1.27 1.27)
					(thickness 0.15)
				)
				(justify left bottom)
				(hide yes)
			)
		)
		(pin "2"
		)
		(pin "3"
		)
		(pin "1"
		)
		(instances
			(project "jetson-orin-baseboard"
				(path ""
					(reference "Q2")
					(unit 1)
				)
			)
		)
	)
	(symbol
		(lib_id "antmicroCapacitors0603:C_10u_0603")
		(at 347.98 190.5 90)
		(mirror x)
		(unit 1)
		(exclude_from_sim no)
		(in_bom yes)
		(on_board yes)
		(dnp no)
		(fields_autoplaced yes)
		(property "Reference" "C51"
			(at 350.52 191.7763 90)
			(effects
				(font
					(size 1.27 1.27)
				)
				(justify right)
			)
		)
		(property "Value" "C_10u_0603"
			(at 358.14 210.82 0)
			(effects
				(font
					(size 1.27 1.27)
					(thickness 0.15)
				)
				(justify left bottom)
				(hide yes)
			)
		)
		(property "Footprint" "antmicro-footprints:C_0603_1608Metric"
			(at 360.68 210.82 0)
			(effects
				(font
					(size 1.27 1.27)
					(thickness 0.15)
				)
				(justify left bottom)
				(hide yes)
			)
		)
		(property "Datasheet" "https://www.murata.com/products/productdetail?partno=GRM188R61A106KE69%23"
			(at 363.22 210.82 0)
			(effects
				(font
					(size 1.27 1.27)
					(thickness 0.15)
				)
				(justify left bottom)
				(hide yes)
			)
		)
		(property "Description" ""
			(at 347.98 190.5 0)
			(effects
				(font
					(size 1.27 1.27)
				)
				(hide yes)
			)
		)
		(property "Manufacturer" "Murata"
			(at 368.3 210.82 0)
			(effects
				(font
					(size 1.27 1.27)
					(thickness 0.15)
				)
				(justify left bottom)
				(hide yes)
			)
		)
		(property "MPN" "GRM188R61A106KE69D"
			(at 365.76 210.82 0)
			(effects
				(font
					(size 1.27 1.27)
					(thickness 0.15)
				)
				(justify left bottom)
				(hide yes)
			)
		)
		(property "Val" "10u"
			(at 350.52 194.3163 90)
			(effects
				(font
					(size 1.27 1.27)
					(thickness 0.15)
				)
				(justify right)
			)
		)
		(property "License" "Apache-2.0"
			(at 370.84 210.82 0)
			(effects
				(font
					(size 1.27 1.27)
					(thickness 0.15)
				)
				(justify left bottom)
				(hide yes)
			)
		)
		(property "Author" "Antmicro"
			(at 373.38 210.82 0)
			(effects
				(font
					(size 1.27 1.27)
					(thickness 0.15)
				)
				(justify left bottom)
				(hide yes)
			)
		)
		(property "Voltage" ""
			(at 375.92 210.82 0)
			(effects
				(font
					(size 1.27 1.27)
				)
				(justify left bottom)
				(hide yes)
			)
		)
		(property "Dielectric" "template_dielectric"
			(at 378.46 210.82 0)
			(effects
				(font
					(size 1.27 1.27)
				)
				(justify left bottom)
				(hide yes)
			)
		)
		(pin "1"
		)
		(pin "2"
		)
		(instances
			(project "jetson-orin-baseboard"
				(path ""
					(reference "C51")
					(unit 1)
				)
			)
		)
	)
	(symbol
		(lib_id "antmicroResistors0402:R_0R_0402")
		(at 83.82 168.91 0)
		(unit 1)
		(exclude_from_sim no)
		(in_bom yes)
		(on_board yes)
		(dnp no)
		(property "Reference" "R225"
			(at 88.9 168.275 0)
			(effects
				(font
					(size 1.27 1.27)
				)
				(justify left bottom)
			)
		)
		(property "Value" "R_0R_0402"
			(at 104.14 181.61 0)
			(effects
				(font
					(size 1.27 1.27)
					(thickness 0.15)
				)
				(justify left bottom)
				(hide yes)
			)
		)
		(property "Footprint" "antmicro-footprints:R_0402_1005Metric"
			(at 104.14 184.15 0)
			(effects
				(font
					(size 1.27 1.27)
					(thickness 0.15)
				)
				(justify left bottom)
				(hide yes)
			)
		)
		(property "Datasheet" "https://industrial.panasonic.com/cdbs/www-data/pdf/RDA0000/AOA0000C301.pdf"
			(at 104.14 186.69 0)
			(effects
				(font
					(size 1.27 1.27)
					(thickness 0.15)
				)
				(justify left bottom)
				(hide yes)
			)
		)
		(property "Description" ""
			(at 83.82 168.91 0)
			(effects
				(font
					(size 1.27 1.27)
				)
				(hide yes)
			)
		)
		(property "Manufacturer" "Panasonic"
			(at 104.14 191.77 0)
			(effects
				(font
					(size 1.27 1.27)
					(thickness 0.15)
				)
				(justify left bottom)
				(hide yes)
			)
		)
		(property "MPN" "ERJ2GE0R00X"
			(at 104.14 189.23 0)
			(effects
				(font
					(size 1.27 1.27)
					(thickness 0.15)
				)
				(justify left bottom)
				(hide yes)
			)
		)
		(property "Val" "0R"
			(at 81.28 168.275 0)
			(effects
				(font
					(size 1.27 1.27)
					(thickness 0.15)
				)
				(justify left bottom)
			)
		)
		(property "License" "Apache-2.0"
			(at 104.14 194.31 0)
			(effects
				(font
					(size 1.27 1.27)
					(thickness 0.15)
				)
				(justify left bottom)
				(hide yes)
			)
		)
		(property "Author" "Antmicro"
			(at 104.14 196.85 0)
			(effects
				(font
					(size 1.27 1.27)
					(thickness 0.15)
				)
				(justify left bottom)
				(hide yes)
			)
		)
		(property "Tolerance" "~"
			(at 104.14 179.07 0)
			(effects
				(font
					(size 1.27 1.27)
				)
				(justify left bottom)
				(hide yes)
			)
		)
		(property "Current" "1A"
			(at 104.14 199.39 0)
			(effects
				(font
					(size 1.27 1.27)
					(thickness 0.15)
				)
				(justify left bottom)
				(hide yes)
			)
		)
		(pin "1"
		)
		(pin "2"
		)
		(instances
			(project "jetson-orin-baseboard"
				(path ""
					(reference "R225")
					(unit 1)
				)
			)
		)
	)
	(symbol
		(lib_id "antmicroCapacitors0402:C_100n_0402")
		(at 74.93 121.92 0)
		(mirror y)
		(unit 1)
		(exclude_from_sim no)
		(in_bom yes)
		(on_board yes)
		(dnp no)
		(property "Reference" "C87"
			(at 73.66 121.285 0)
			(effects
				(font
					(size 1.27 1.27)
				)
				(justify right bottom)
			)
		)
		(property "Value" "C_100n_0402"
			(at 54.61 132.08 0)
			(effects
				(font
					(size 1.27 1.27)
					(thickness 0.15)
				)
				(justify left bottom)
				(hide yes)
			)
		)
		(property "Footprint" "antmicro-footprints:C_0402_1005Metric"
			(at 54.61 134.62 0)
			(effects
				(font
					(size 1.27 1.27)
					(thickness 0.15)
				)
				(justify left bottom)
				(hide yes)
			)
		)
		(property "Datasheet" "https://www.murata.com/products/productdetail?partno=GRM155R61H104KE14%23"
			(at 54.61 137.16 0)
			(effects
				(font
					(size 1.27 1.27)
					(thickness 0.15)
				)
				(justify left bottom)
				(hide yes)
			)
		)
		(property "Description" ""
			(at 74.93 121.92 0)
			(effects
				(font
					(size 1.27 1.27)
				)
				(hide yes)
			)
		)
		(property "Manufacturer" "Murata"
			(at 54.61 142.24 0)
			(effects
				(font
					(size 1.27 1.27)
					(thickness 0.15)
				)
				(justify left bottom)
				(hide yes)
			)
		)
		(property "MPN" "GRM155R61H104KE14D"
			(at 54.61 139.7 0)
			(effects
				(font
					(size 1.27 1.27)
					(thickness 0.15)
				)
				(justify left bottom)
				(hide yes)
			)
		)
		(property "Val" "100n"
			(at 71.12 123.825 0)
			(effects
				(font
					(size 1.27 1.27)
					(thickness 0.15)
				)
				(justify left bottom)
			)
		)
		(property "License" "Apache-2.0"
			(at 54.61 144.78 0)
			(effects
				(font
					(size 1.27 1.27)
					(thickness 0.15)
				)
				(justify left bottom)
				(hide yes)
			)
		)
		(property "Author" "Antmicro"
			(at 54.61 147.32 0)
			(effects
				(font
					(size 1.27 1.27)
					(thickness 0.15)
				)
				(justify left bottom)
				(hide yes)
			)
		)
		(property "Voltage" "50V"
			(at 54.61 149.86 0)
			(effects
				(font
					(size 1.27 1.27)
				)
				(justify left bottom)
				(hide yes)
			)
		)
		(property "Dielectric" "X5R"
			(at 54.61 152.4 0)
			(effects
				(font
					(size 1.27 1.27)
				)
				(justify left bottom)
				(hide yes)
			)
		)
		(pin "1"
		)
		(pin "2"
		)
		(instances
			(project "jetson-orin-baseboard"
				(path ""
					(reference "C87")
					(unit 1)
				)
			)
		)
	)
	(symbol
		(lib_id "antmicroResistors0402:R_2k2_0402")
		(at 260.35 179.07 270)
		(mirror x)
		(unit 1)
		(exclude_from_sim no)
		(in_bom no)
		(on_board yes)
		(dnp yes)
		(property "Reference" "R280"
			(at 261.62 175.26 90)
			(effects
				(font
					(size 1.27 1.27)
				)
				(justify left)
			)
		)
		(property "Value" "R_2k2_0402"
			(at 247.65 158.75 0)
			(effects
				(font
					(size 1.27 1.27)
					(thickness 0.15)
				)
				(justify left bottom)
				(hide yes)
			)
		)
		(property "Footprint" "antmicro-footprints:R_0402_1005Metric"
			(at 245.11 158.75 0)
			(effects
				(font
					(size 1.27 1.27)
					(thickness 0.15)
				)
				(justify left bottom)
				(hide yes)
			)
		)
		(property "Datasheet" "https://www.bourns.com/docs/product-datasheets/cr.pdf"
			(at 242.57 158.75 0)
			(effects
				(font
					(size 1.27 1.27)
					(thickness 0.15)
				)
				(justify left bottom)
				(hide yes)
			)
		)
		(property "Description" ""
			(at 260.35 179.07 0)
			(effects
				(font
					(size 1.27 1.27)
				)
				(hide yes)
			)
		)
		(property "Manufacturer" "Bourns"
			(at 237.49 158.75 0)
			(effects
				(font
					(size 1.27 1.27)
					(thickness 0.15)
				)
				(justify left bottom)
				(hide yes)
			)
		)
		(property "MPN" "CR0402-FX-2201GLF"
			(at 240.03 158.75 0)
			(effects
				(font
					(size 1.27 1.27)
					(thickness 0.15)
				)
				(justify left bottom)
				(hide yes)
			)
		)
		(property "Val" "2k2"
			(at 261.62 177.8 90)
			(effects
				(font
					(size 1.27 1.27)
					(thickness 0.15)
				)
				(justify left)
			)
		)
		(property "License" "Apache-2.0"
			(at 234.95 158.75 0)
			(effects
				(font
					(size 1.27 1.27)
					(thickness 0.15)
				)
				(justify left bottom)
				(hide yes)
			)
		)
		(property "Author" "Antmicro"
			(at 232.41 158.75 0)
			(effects
				(font
					(size 1.27 1.27)
					(thickness 0.15)
				)
				(justify left bottom)
				(hide yes)
			)
		)
		(property "Tolerance" "1%"
			(at 250.19 158.75 0)
			(effects
				(font
					(size 1.27 1.27)
				)
				(justify left bottom)
				(hide yes)
			)
		)
		(pin "1"
		)
		(pin "2"
		)
		(instances
			(project "jetson-orin-baseboard"
				(path ""
					(reference "R280")
					(unit 1)
				)
			)
		)
	)
	(symbol
		(lib_id "antmicroResistors0402:R_499R_0402")
		(at 186.69 185.42 90)
		(unit 1)
		(exclude_from_sim no)
		(in_bom yes)
		(on_board yes)
		(dnp no)
		(property "Reference" "R220"
			(at 187.96 181.61 90)
			(effects
				(font
					(size 1.27 1.27)
					(thickness 0.15)
				)
				(justify right)
			)
		)
		(property "Value" "R_499R_0402"
			(at 199.39 165.1 0)
			(effects
				(font
					(size 1.27 1.27)
					(thickness 0.15)
				)
				(justify left bottom)
				(hide yes)
			)
		)
		(property "Footprint" "antmicro-footprints:R_0402_1005Metric"
			(at 201.93 165.1 0)
			(effects
				(font
					(size 1.27 1.27)
					(thickness 0.15)
				)
				(justify left bottom)
				(hide yes)
			)
		)
		(property "Datasheet" "https://www.mouser.com/datasheet/2/54/cr-1858361.pdf"
			(at 204.47 165.1 0)
			(effects
				(font
					(size 1.27 1.27)
					(thickness 0.15)
				)
				(justify left bottom)
				(hide yes)
			)
		)
		(property "Description" ""
			(at 186.69 185.42 0)
			(effects
				(font
					(size 1.27 1.27)
				)
				(hide yes)
			)
		)
		(property "MPN" "CR0402-FX-4990GLF"
			(at 207.01 165.1 0)
			(effects
				(font
					(size 1.27 1.27)
					(thickness 0.15)
				)
				(justify left bottom)
				(hide yes)
			)
		)
		(property "Manufacturer" "Bourns"
			(at 209.55 165.1 0)
			(effects
				(font
					(size 1.27 1.27)
					(thickness 0.15)
				)
				(justify left bottom)
				(hide yes)
			)
		)
		(property "License" "Apache-2.0"
			(at 212.09 165.1 0)
			(effects
				(font
					(size 1.27 1.27)
					(thickness 0.15)
				)
				(justify left bottom)
				(hide yes)
			)
		)
		(property "Author" "Antmicro"
			(at 214.63 165.1 0)
			(effects
				(font
					(size 1.27 1.27)
					(thickness 0.15)
				)
				(justify left bottom)
				(hide yes)
			)
		)
		(property "Val" "499R"
			(at 187.96 184.15 90)
			(effects
				(font
					(size 1.27 1.27)
					(thickness 0.15)
				)
				(justify right)
			)
		)
		(property "Tolerance" "1%"
			(at 196.85 165.1 0)
			(effects
				(font
					(size 1.27 1.27)
				)
				(justify left bottom)
				(hide yes)
			)
		)
		(pin "1"
		)
		(pin "2"
		)
		(instances
			(project "jetson-orin-baseboard"
				(path ""
					(reference "R220")
					(unit 1)
				)
			)
		)
	)
	(symbol
		(lib_id "antmicroTestPoints:TP_0.75mm_SMD")
		(at 344.17 175.26 180)
		(unit 1)
		(exclude_from_sim no)
		(in_bom no)
		(on_board yes)
		(dnp no)
		(property "Reference" "TP58"
			(at 337.82 175.26 0)
			(effects
				(font
					(size 1.27 1.27)
				)
			)
		)
		(property "Value" "TP_0.75mm_SMD"
			(at 334.01 171.45 0)
			(effects
				(font
					(size 1.27 1.27)
					(thickness 0.15)
				)
				(justify left bottom)
				(hide yes)
			)
		)
		(property "Footprint" "antmicro-footprints:TP_SMD_0.75mm"
			(at 334.01 168.91 0)
			(effects
				(font
					(size 1.27 1.27)
					(thickness 0.15)
				)
				(justify left bottom)
				(hide yes)
			)
		)
		(property "Datasheet" ""
			(at 326.39 162.56 0)
			(effects
				(font
					(size 1.27 1.27)
					(thickness 0.15)
				)
				(justify left bottom)
				(hide yes)
			)
		)
		(property "Description" ""
			(at 344.17 175.26 0)
			(effects
				(font
					(size 1.27 1.27)
				)
				(hide yes)
			)
		)
		(property "MPN" ""
			(at 333.375 163.83 0)
			(effects
				(font
					(size 1.27 1.27)
					(thickness 0.15)
				)
				(justify left bottom)
				(hide yes)
			)
		)
		(property "Manufacturer" ""
			(at 333.375 168.91 0)
			(effects
				(font
					(size 1.27 1.27)
					(thickness 0.15)
				)
				(justify left bottom)
				(hide yes)
			)
		)
		(property "Author" "Antmicro"
			(at 334.01 166.37 0)
			(effects
				(font
					(size 1.27 1.27)
					(thickness 0.15)
				)
				(justify left bottom)
				(hide yes)
			)
		)
		(property "License" "Apache-2.0"
			(at 334.01 163.83 0)
			(effects
				(font
					(size 1.27 1.27)
					(thickness 0.15)
				)
				(justify left bottom)
				(hide yes)
			)
		)
		(pin "1"
		)
		(instances
			(project "jetson-orin-baseboard"
				(path ""
					(reference "TP58")
					(unit 1)
				)
			)
		)
	)
	(symbol
		(lib_id "antmicroResistors0402:R_10k_0402")
		(at 87.63 165.1 90)
		(unit 1)
		(exclude_from_sim no)
		(in_bom yes)
		(on_board yes)
		(dnp no)
		(property "Reference" "R211"
			(at 88.9 161.29 90)
			(effects
				(font
					(size 1.27 1.27)
				)
				(justify right)
			)
		)
		(property "Value" "R_10k_0402"
			(at 100.33 144.78 0)
			(effects
				(font
					(size 1.27 1.27)
					(thickness 0.15)
				)
				(justify left bottom)
				(hide yes)
			)
		)
		(property "Footprint" "antmicro-footprints:R_0402_1005Metric"
			(at 102.87 144.78 0)
			(effects
				(font
					(size 1.27 1.27)
					(thickness 0.15)
				)
				(justify left bottom)
				(hide yes)
			)
		)
		(property "Datasheet" "https://www.bourns.com/docs/product-datasheets/cr.pdf"
			(at 105.41 144.78 0)
			(effects
				(font
					(size 1.27 1.27)
					(thickness 0.15)
				)
				(justify left bottom)
				(hide yes)
			)
		)
		(property "Description" ""
			(at 87.63 165.1 0)
			(effects
				(font
					(size 1.27 1.27)
				)
				(hide yes)
			)
		)
		(property "Manufacturer" "Bourns"
			(at 110.49 144.78 0)
			(effects
				(font
					(size 1.27 1.27)
					(thickness 0.15)
				)
				(justify left bottom)
				(hide yes)
			)
		)
		(property "MPN" "CR0402-FX-1002GLF"
			(at 107.95 144.78 0)
			(effects
				(font
					(size 1.27 1.27)
					(thickness 0.15)
				)
				(justify left bottom)
				(hide yes)
			)
		)
		(property "Val" "10k"
			(at 88.9 163.83 90)
			(effects
				(font
					(size 1.27 1.27)
					(thickness 0.15)
				)
				(justify right)
			)
		)
		(property "License" "Apache-2.0"
			(at 113.03 144.78 0)
			(effects
				(font
					(size 1.27 1.27)
					(thickness 0.15)
				)
				(justify left bottom)
				(hide yes)
			)
		)
		(property "Author" "Antmicro"
			(at 115.57 144.78 0)
			(effects
				(font
					(size 1.27 1.27)
					(thickness 0.15)
				)
				(justify left bottom)
				(hide yes)
			)
		)
		(property "Tolerance" "1%"
			(at 97.79 144.78 0)
			(effects
				(font
					(size 1.27 1.27)
				)
				(justify left bottom)
				(hide yes)
			)
		)
		(pin "1"
		)
		(pin "2"
		)
		(instances
			(project "jetson-orin-baseboard"
				(path ""
					(reference "R211")
					(unit 1)
				)
			)
		)
	)
	(symbol
		(lib_id "antmicroResistorNetworksArrays:R_4x0R_0201_array")
		(at 281.94 146.05 180)
		(unit 1)
		(exclude_from_sim no)
		(in_bom yes)
		(on_board yes)
		(dnp no)
		(property "Reference" "R35"
			(at 276.86 133.35 0)
			(effects
				(font
					(size 1.27 1.27)
				)
			)
		)
		(property "Value" "R_4x0R_0201_array"
			(at 255.27 138.43 0)
			(effects
				(font
					(size 1.27 1.27)
					(thickness 0.15)
				)
				(justify left bottom)
				(hide yes)
			)
		)
		(property "Footprint" "antmicro-footprints:R_Array_4x0201_Panasonic_EXB18V"
			(at 255.27 133.35 0)
			(effects
				(font
					(size 1.27 1.27)
					(thickness 0.15)
				)
				(justify left bottom)
				(hide yes)
			)
		)
		(property "Datasheet" "http://industrial.panasonic.com/cdbs/www-data/pdf/AOC0000/AOC0000C14.pdf"
			(at 255.27 130.81 0)
			(effects
				(font
					(size 1.27 1.27)
					(thickness 0.15)
				)
				(justify left bottom)
				(hide yes)
			)
		)
		(property "Description" ""
			(at 281.94 146.05 0)
			(effects
				(font
					(size 1.27 1.27)
				)
				(hide yes)
			)
		)
		(property "MPN" "EXB-18VR000X"
			(at 255.27 128.27 0)
			(effects
				(font
					(size 1.27 1.27)
					(thickness 0.15)
				)
				(justify left bottom)
				(hide yes)
			)
		)
		(property "Manufacturer" "Panasonic"
			(at 255.27 125.73 0)
			(effects
				(font
					(size 1.27 1.27)
					(thickness 0.15)
				)
				(justify left bottom)
				(hide yes)
			)
		)
		(property "Val" "4x0R_0201"
			(at 276.86 135.255 0)
			(effects
				(font
					(size 1.27 1.27)
					(thickness 0.15)
				)
			)
		)
		(property "Author" "Antmicro"
			(at 255.27 123.19 0)
			(effects
				(font
					(size 1.27 1.27)
					(thickness 0.15)
				)
				(justify left bottom)
				(hide yes)
			)
		)
		(property "License" "Apache-2.0"
			(at 255.27 120.65 0)
			(effects
				(font
					(size 1.27 1.27)
					(thickness 0.15)
				)
				(justify left bottom)
				(hide yes)
			)
		)
		(pin "1"
		)
		(pin "2"
		)
		(pin "3"
		)
		(pin "4"
		)
		(pin "5"
		)
		(pin "6"
		)
		(pin "7"
		)
		(pin "8"
		)
		(instances
			(project "jetson-orin-baseboard"
				(path ""
					(reference "R35")
					(unit 1)
				)
			)
		)
	)
	(symbol
		(lib_id "antmicroResistors0402:R_499R_0402")
		(at 154.94 185.42 90)
		(unit 1)
		(exclude_from_sim no)
		(in_bom yes)
		(on_board yes)
		(dnp no)
		(property "Reference" "R210"
			(at 156.21 181.61 90)
			(effects
				(font
					(size 1.27 1.27)
					(thickness 0.15)
				)
				(justify right)
			)
		)
		(property "Value" "R_499R_0402"
			(at 167.64 165.1 0)
			(effects
				(font
					(size 1.27 1.27)
					(thickness 0.15)
				)
				(justify left bottom)
				(hide yes)
			)
		)
		(property "Footprint" "antmicro-footprints:R_0402_1005Metric"
			(at 170.18 165.1 0)
			(effects
				(font
					(size 1.27 1.27)
					(thickness 0.15)
				)
				(justify left bottom)
				(hide yes)
			)
		)
		(property "Datasheet" "https://www.mouser.com/datasheet/2/54/cr-1858361.pdf"
			(at 172.72 165.1 0)
			(effects
				(font
					(size 1.27 1.27)
					(thickness 0.15)
				)
				(justify left bottom)
				(hide yes)
			)
		)
		(property "Description" ""
			(at 154.94 185.42 0)
			(effects
				(font
					(size 1.27 1.27)
				)
				(hide yes)
			)
		)
		(property "MPN" "CR0402-FX-4990GLF"
			(at 175.26 165.1 0)
			(effects
				(font
					(size 1.27 1.27)
					(thickness 0.15)
				)
				(justify left bottom)
				(hide yes)
			)
		)
		(property "Manufacturer" "Bourns"
			(at 177.8 165.1 0)
			(effects
				(font
					(size 1.27 1.27)
					(thickness 0.15)
				)
				(justify left bottom)
				(hide yes)
			)
		)
		(property "License" "Apache-2.0"
			(at 180.34 165.1 0)
			(effects
				(font
					(size 1.27 1.27)
					(thickness 0.15)
				)
				(justify left bottom)
				(hide yes)
			)
		)
		(property "Author" "Antmicro"
			(at 182.88 165.1 0)
			(effects
				(font
					(size 1.27 1.27)
					(thickness 0.15)
				)
				(justify left bottom)
				(hide yes)
			)
		)
		(property "Val" "499R"
			(at 156.21 184.15 90)
			(effects
				(font
					(size 1.27 1.27)
					(thickness 0.15)
				)
				(justify right)
			)
		)
		(property "Tolerance" "1%"
			(at 165.1 165.1 0)
			(effects
				(font
					(size 1.27 1.27)
				)
				(justify left bottom)
				(hide yes)
			)
		)
		(pin "1"
		)
		(pin "2"
		)
		(instances
			(project "jetson-orin-baseboard"
				(path ""
					(reference "R210")
					(unit 1)
				)
			)
		)
	)
	(symbol
		(lib_id "antmicropower:+3V3")
		(at 76.2 180.34 0)
		(unit 1)
		(exclude_from_sim no)
		(in_bom yes)
		(on_board yes)
		(dnp no)
		(property "Reference" "#PWR0329"
			(at 76.2 184.15 0)
			(effects
				(font
					(size 1.27 1.27)
				)
				(justify left bottom)
				(hide yes)
			)
		)
		(property "Value" "+3V3"
			(at 73.025 177.165 0)
			(effects
				(font
					(size 1.27 1.27)
					(thickness 0.15)
				)
				(justify left bottom)
			)
		)
		(property "Footprint" ""
			(at 91.44 187.96 0)
			(effects
				(font
					(size 1.27 1.27)
					(thickness 0.15)
				)
				(justify left bottom)
				(hide yes)
			)
		)
		(property "Datasheet" ""
			(at 91.44 190.5 0)
			(effects
				(font
					(size 1.27 1.27)
					(thickness 0.15)
				)
				(justify left bottom)
				(hide yes)
			)
		)
		(property "Description" ""
			(at 76.2 180.34 0)
			(effects
				(font
					(size 1.27 1.27)
				)
				(hide yes)
			)
		)
		(property "Author" "Antmicro"
			(at 91.44 182.88 0)
			(effects
				(font
					(size 1.27 1.27)
					(thickness 0.15)
				)
				(justify left bottom)
				(hide yes)
			)
		)
		(property "License" "Apache-2.0"
			(at 91.44 185.42 0)
			(effects
				(font
					(size 1.27 1.27)
					(thickness 0.15)
				)
				(justify left bottom)
				(hide yes)
			)
		)
		(pin "1"
		)
		(instances
			(project "jetson-orin-baseboard"
				(path ""
					(reference "#PWR0329")
					(unit 1)
				)
			)
		)
	)
	(symbol
		(lib_id "antmicroDiodesRectifiersSingle:RB521S30T1G")
		(at 328.93 187.96 180)
		(unit 1)
		(exclude_from_sim no)
		(in_bom yes)
		(on_board yes)
		(dnp no)
		(property "Reference" "D38"
			(at 326.39 182.88 0)
			(effects
				(font
					(size 1.27 1.27)
				)
			)
		)
		(property "Value" "RB521S30T1G"
			(at 306.07 172.72 0)
			(effects
				(font
					(size 1.27 1.27)
					(thickness 0.15)
				)
				(justify left bottom)
				(hide yes)
			)
		)
		(property "Footprint" "antmicro-footprints:SOD-523"
			(at 306.07 177.8 0)
			(effects
				(font
					(size 1.27 1.27)
					(thickness 0.15)
				)
				(justify left bottom)
				(hide yes)
			)
		)
		(property "Datasheet" "https://www.onsemi.com/pdf/datasheet/rb521s30t1-d.pdf"
			(at 306.07 175.26 0)
			(effects
				(font
					(size 1.27 1.27)
					(thickness 0.15)
				)
				(justify left bottom)
				(hide yes)
			)
		)
		(property "Description" ""
			(at 328.93 187.96 0)
			(effects
				(font
					(size 1.27 1.27)
				)
				(hide yes)
			)
		)
		(property "MPN" "RB521S30T1G"
			(at 326.39 185.42 0)
			(effects
				(font
					(size 1.27 1.27)
					(thickness 0.15)
				)
			)
		)
		(property "Manufacturer" "ON Semiconductor"
			(at 306.07 170.18 0)
			(effects
				(font
					(size 1.27 1.27)
					(thickness 0.15)
				)
				(justify left bottom)
				(hide yes)
			)
		)
		(property "Author" "Antmicro"
			(at 306.07 167.64 0)
			(effects
				(font
					(size 1.27 1.27)
					(thickness 0.15)
				)
				(justify left bottom)
				(hide yes)
			)
		)
		(property "License" "Apache-2.0"
			(at 306.07 165.1 0)
			(effects
				(font
					(size 1.27 1.27)
					(thickness 0.15)
				)
				(justify left bottom)
				(hide yes)
			)
		)
		(pin "1"
		)
		(pin "2"
		)
		(instances
			(project "jetson-orin-baseboard"
				(path ""
					(reference "D38")
					(unit 1)
				)
			)
		)
	)
	(symbol
		(lib_id "antmicropower:+1V8")
		(at 46.99 154.94 0)
		(unit 1)
		(exclude_from_sim no)
		(in_bom yes)
		(on_board yes)
		(dnp no)
		(property "Reference" "#PWR013"
			(at 46.99 158.75 0)
			(effects
				(font
					(size 1.27 1.27)
				)
				(justify left bottom)
				(hide yes)
			)
		)
		(property "Value" "+1V8"
			(at 43.815 151.765 0)
			(effects
				(font
					(size 1.27 1.27)
					(thickness 0.15)
				)
				(justify left bottom)
			)
		)
		(property "Footprint" ""
			(at 62.23 162.56 0)
			(effects
				(font
					(size 1.27 1.27)
					(thickness 0.15)
				)
				(justify left bottom)
				(hide yes)
			)
		)
		(property "Datasheet" ""
			(at 62.23 165.1 0)
			(effects
				(font
					(size 1.27 1.27)
					(thickness 0.15)
				)
				(justify left bottom)
				(hide yes)
			)
		)
		(property "Description" ""
			(at 46.99 154.94 0)
			(effects
				(font
					(size 1.27 1.27)
				)
				(hide yes)
			)
		)
		(property "Author" "Antmicro"
			(at 62.23 160.02 0)
			(effects
				(font
					(size 1.27 1.27)
					(thickness 0.15)
				)
				(justify left bottom)
				(hide yes)
			)
		)
		(property "License" "Apache-2.0"
			(at 62.23 162.56 0)
			(effects
				(font
					(size 1.27 1.27)
					(thickness 0.15)
				)
				(justify left bottom)
				(hide yes)
			)
		)
		(pin "1"
		)
		(instances
			(project "jetson-orin-baseboard"
				(path ""
					(reference "#PWR013")
					(unit 1)
				)
			)
		)
	)
	(symbol
		(lib_id "antmicropower:GND")
		(at 384.81 189.23 0)
		(unit 1)
		(exclude_from_sim no)
		(in_bom yes)
		(on_board yes)
		(dnp no)
		(property "Reference" "#PWR0287"
			(at 384.81 195.58 0)
			(effects
				(font
					(size 1.27 1.27)
				)
				(justify left bottom)
				(hide yes)
			)
		)
		(property "Value" "GND"
			(at 384.81 193.04 0)
			(effects
				(font
					(size 1.27 1.27)
					(thickness 0.15)
				)
			)
		)
		(property "Footprint" ""
			(at 393.7 196.85 0)
			(effects
				(font
					(size 1.27 1.27)
					(thickness 0.15)
				)
				(justify left bottom)
				(hide yes)
			)
		)
		(property "Datasheet" ""
			(at 393.7 201.93 0)
			(effects
				(font
					(size 1.27 1.27)
					(thickness 0.15)
				)
				(justify left bottom)
				(hide yes)
			)
		)
		(property "Description" ""
			(at 384.81 189.23 0)
			(effects
				(font
					(size 1.27 1.27)
				)
				(hide yes)
			)
		)
		(property "Author" "Antmicro"
			(at 393.7 196.85 0)
			(effects
				(font
					(size 1.27 1.27)
					(thickness 0.15)
				)
				(justify left bottom)
				(hide yes)
			)
		)
		(property "License" "Apache-2.0"
			(at 393.7 199.39 0)
			(effects
				(font
					(size 1.27 1.27)
					(thickness 0.15)
				)
				(justify left bottom)
				(hide yes)
			)
		)
		(pin "1"
		)
		(instances
			(project "jetson-orin-baseboard"
				(path ""
					(reference "#PWR0287")
					(unit 1)
				)
			)
		)
	)
	(symbol
		(lib_id "antmicroTVSDiodes:TPD4E05U06QDQARQ1")
		(at 314.96 43.18 0)
		(unit 1)
		(exclude_from_sim no)
		(in_bom yes)
		(on_board yes)
		(dnp no)
		(fields_autoplaced yes)
		(property "Reference" "U44"
			(at 325.12 46.355 0)
			(effects
				(font
					(size 1.27 1.27)
				)
				(justify left)
			)
		)
		(property "Value" "TPD4E05U06QDQARQ1"
			(at 339.09 53.34 0)
			(effects
				(font
					(size 1.27 1.27)
					(thickness 0.15)
				)
				(justify left bottom)
				(hide yes)
			)
		)
		(property "Footprint" "antmicro-footprints:USON-10_2.5x1mm_P0.5mm"
			(at 339.09 48.26 0)
			(effects
				(font
					(size 1.27 1.27)
					(thickness 0.15)
				)
				(justify left bottom)
				(hide yes)
			)
		)
		(property "Datasheet" "https://www.ti.com/lit/ds/symlink/tpd4e05u06-q1.pdf?HQS=dis-mous-null-mousermode-dsf-pf-null-wwe&ts=1663591265741&ref_url=https%253A%252F%252Fwww.mouser.com%252F"
			(at 339.09 50.8 0)
			(effects
				(font
					(size 1.27 1.27)
					(thickness 0.15)
				)
				(justify left bottom)
				(hide yes)
			)
		)
		(property "Description" ""
			(at 314.96 43.18 0)
			(effects
				(font
					(size 1.27 1.27)
				)
				(hide yes)
			)
		)
		(property "Manufacturer" "Texas Instruments"
			(at 339.09 55.88 0)
			(effects
				(font
					(size 1.27 1.27)
					(thickness 0.15)
				)
				(justify left bottom)
				(hide yes)
			)
		)
		(property "MPN" "TPD4E05U06QDQARQ1"
			(at 325.12 48.895 0)
			(effects
				(font
					(size 1.27 1.27)
					(thickness 0.15)
				)
				(justify left)
			)
		)
		(property "Author" "Antmicro"
			(at 339.09 58.42 0)
			(effects
				(font
					(size 1.27 1.27)
					(thickness 0.15)
				)
				(justify left bottom)
				(hide yes)
			)
		)
		(property "License" "Apache-2.0"
			(at 339.09 60.96 0)
			(effects
				(font
					(size 1.27 1.27)
					(thickness 0.15)
				)
				(justify left bottom)
				(hide yes)
			)
		)
		(pin "1"
		)
		(pin "10"
		)
		(pin "2"
		)
		(pin "3"
		)
		(pin "4"
		)
		(pin "5"
		)
		(pin "6"
		)
		(pin "7"
		)
		(pin "8"
		)
		(pin "9"
		)
		(instances
			(project "jetson-orin-baseboard"
				(path ""
					(reference "U44")
					(unit 1)
				)
			)
		)
	)
	(symbol
		(lib_id "antmicroTestPoints:TP_0.75mm_SMD")
		(at 30.48 167.64 270)
		(unit 1)
		(exclude_from_sim no)
		(in_bom no)
		(on_board yes)
		(dnp no)
		(property "Reference" "TP21"
			(at 31.115 170.815 90)
			(effects
				(font
					(size 1.27 1.27)
				)
				(justify left)
			)
		)
		(property "Value" "TP_0.75mm_SMD"
			(at 26.67 177.8 0)
			(effects
				(font
					(size 1.27 1.27)
					(thickness 0.15)
				)
				(justify left bottom)
				(hide yes)
			)
		)
		(property "Footprint" "antmicro-footprints:TP_SMD_0.75mm"
			(at 24.13 177.8 0)
			(effects
				(font
					(size 1.27 1.27)
					(thickness 0.15)
				)
				(justify left bottom)
				(hide yes)
			)
		)
		(property "Datasheet" ""
			(at 17.78 185.42 0)
			(effects
				(font
					(size 1.27 1.27)
					(thickness 0.15)
				)
				(justify left bottom)
				(hide yes)
			)
		)
		(property "Description" ""
			(at 30.48 167.64 0)
			(effects
				(font
					(size 1.27 1.27)
				)
				(hide yes)
			)
		)
		(property "MPN" ""
			(at 19.05 178.435 0)
			(effects
				(font
					(size 1.27 1.27)
					(thickness 0.15)
				)
				(justify left bottom)
				(hide yes)
			)
		)
		(property "Manufacturer" ""
			(at 24.13 178.435 0)
			(effects
				(font
					(size 1.27 1.27)
					(thickness 0.15)
				)
				(justify left bottom)
				(hide yes)
			)
		)
		(property "Author" "Antmicro"
			(at 21.59 177.8 0)
			(effects
				(font
					(size 1.27 1.27)
					(thickness 0.15)
				)
				(justify left bottom)
				(hide yes)
			)
		)
		(property "License" "Apache-2.0"
			(at 19.05 177.8 0)
			(effects
				(font
					(size 1.27 1.27)
					(thickness 0.15)
				)
				(justify left bottom)
				(hide yes)
			)
		)
		(pin "1"
		)
		(instances
			(project "jetson-orin-baseboard"
				(path ""
					(reference "TP21")
					(unit 1)
				)
			)
		)
	)
	(symbol
		(lib_id "antmicroCapacitors0402:C_100n_0402")
		(at 260.35 198.12 270)
		(mirror x)
		(unit 1)
		(exclude_from_sim no)
		(in_bom yes)
		(on_board yes)
		(dnp no)
		(fields_autoplaced yes)
		(property "Reference" "C163"
			(at 262.89 194.3036 90)
			(effects
				(font
					(size 1.27 1.27)
				)
				(justify left)
			)
		)
		(property "Value" "C_100n_0402"
			(at 250.19 177.8 0)
			(effects
				(font
					(size 1.27 1.27)
					(thickness 0.15)
				)
				(justify left bottom)
				(hide yes)
			)
		)
		(property "Footprint" "antmicro-footprints:C_0402_1005Metric"
			(at 247.65 177.8 0)
			(effects
				(font
					(size 1.27 1.27)
					(thickness 0.15)
				)
				(justify left bottom)
				(hide yes)
			)
		)
		(property "Datasheet" "https://www.murata.com/products/productdetail?partno=GRM155R61H104KE14%23"
			(at 245.11 177.8 0)
			(effects
				(font
					(size 1.27 1.27)
					(thickness 0.15)
				)
				(justify left bottom)
				(hide yes)
			)
		)
		(property "Description" ""
			(at 260.35 198.12 0)
			(effects
				(font
					(size 1.27 1.27)
				)
				(hide yes)
			)
		)
		(property "Manufacturer" "Murata"
			(at 240.03 177.8 0)
			(effects
				(font
					(size 1.27 1.27)
					(thickness 0.15)
				)
				(justify left bottom)
				(hide yes)
			)
		)
		(property "MPN" "GRM155R61H104KE14D"
			(at 242.57 177.8 0)
			(effects
				(font
					(size 1.27 1.27)
					(thickness 0.15)
				)
				(justify left bottom)
				(hide yes)
			)
		)
		(property "Val" "100n"
			(at 262.89 196.8436 90)
			(effects
				(font
					(size 1.27 1.27)
					(thickness 0.15)
				)
				(justify left)
			)
		)
		(property "License" "Apache-2.0"
			(at 237.49 177.8 0)
			(effects
				(font
					(size 1.27 1.27)
					(thickness 0.15)
				)
				(justify left bottom)
				(hide yes)
			)
		)
		(property "Author" "Antmicro"
			(at 234.95 177.8 0)
			(effects
				(font
					(size 1.27 1.27)
					(thickness 0.15)
				)
				(justify left bottom)
				(hide yes)
			)
		)
		(property "Voltage" "50V"
			(at 232.41 177.8 0)
			(effects
				(font
					(size 1.27 1.27)
				)
				(justify left bottom)
				(hide yes)
			)
		)
		(property "Dielectric" "X5R"
			(at 229.87 177.8 0)
			(effects
				(font
					(size 1.27 1.27)
				)
				(justify left bottom)
				(hide yes)
			)
		)
		(pin "1"
		)
		(pin "2"
		)
		(instances
			(project "jetson-orin-baseboard"
				(path ""
					(reference "C163")
					(unit 1)
				)
			)
		)
	)
	(symbol
		(lib_id "antmicropower:+3V3")
		(at 66.04 154.94 0)
		(unit 1)
		(exclude_from_sim no)
		(in_bom yes)
		(on_board yes)
		(dnp no)
		(property "Reference" "#PWR014"
			(at 66.04 158.75 0)
			(effects
				(font
					(size 1.27 1.27)
				)
				(justify left bottom)
				(hide yes)
			)
		)
		(property "Value" "+3V3"
			(at 62.865 151.765 0)
			(effects
				(font
					(size 1.27 1.27)
					(thickness 0.15)
				)
				(justify left bottom)
			)
		)
		(property "Footprint" ""
			(at 81.28 162.56 0)
			(effects
				(font
					(size 1.27 1.27)
					(thickness 0.15)
				)
				(justify left bottom)
				(hide yes)
			)
		)
		(property "Datasheet" ""
			(at 81.28 165.1 0)
			(effects
				(font
					(size 1.27 1.27)
					(thickness 0.15)
				)
				(justify left bottom)
				(hide yes)
			)
		)
		(property "Description" ""
			(at 66.04 154.94 0)
			(effects
				(font
					(size 1.27 1.27)
				)
				(hide yes)
			)
		)
		(property "Author" "Antmicro"
			(at 81.28 157.48 0)
			(effects
				(font
					(size 1.27 1.27)
					(thickness 0.15)
				)
				(justify left bottom)
				(hide yes)
			)
		)
		(property "License" "Apache-2.0"
			(at 81.28 160.02 0)
			(effects
				(font
					(size 1.27 1.27)
					(thickness 0.15)
				)
				(justify left bottom)
				(hide yes)
			)
		)
		(pin "1"
		)
		(instances
			(project "jetson-orin-baseboard"
				(path ""
					(reference "#PWR014")
					(unit 1)
				)
			)
		)
	)
	(symbol
		(lib_id "antmicropower:GND")
		(at 347.98 196.85 0)
		(unit 1)
		(exclude_from_sim no)
		(in_bom yes)
		(on_board yes)
		(dnp no)
		(property "Reference" "#PWR0177"
			(at 347.98 203.2 0)
			(effects
				(font
					(size 1.27 1.27)
				)
				(justify left bottom)
				(hide yes)
			)
		)
		(property "Value" "GND"
			(at 347.98 200.66 0)
			(effects
				(font
					(size 1.27 1.27)
					(thickness 0.15)
				)
			)
		)
		(property "Footprint" ""
			(at 356.87 204.47 0)
			(effects
				(font
					(size 1.27 1.27)
					(thickness 0.15)
				)
				(justify left bottom)
				(hide yes)
			)
		)
		(property "Datasheet" ""
			(at 356.87 209.55 0)
			(effects
				(font
					(size 1.27 1.27)
					(thickness 0.15)
				)
				(justify left bottom)
				(hide yes)
			)
		)
		(property "Description" ""
			(at 347.98 196.85 0)
			(effects
				(font
					(size 1.27 1.27)
				)
				(hide yes)
			)
		)
		(property "Author" "Antmicro"
			(at 356.87 204.47 0)
			(effects
				(font
					(size 1.27 1.27)
					(thickness 0.15)
				)
				(justify left bottom)
				(hide yes)
			)
		)
		(property "License" "Apache-2.0"
			(at 356.87 207.01 0)
			(effects
				(font
					(size 1.27 1.27)
					(thickness 0.15)
				)
				(justify left bottom)
				(hide yes)
			)
		)
		(pin "1"
		)
		(instances
			(project "jetson-orin-baseboard"
				(path ""
					(reference "#PWR0177")
					(unit 1)
				)
			)
		)
	)
	(symbol
		(lib_id "antmicroResistors0402:R_2k2_0402")
		(at 308.61 231.14 90)
		(unit 1)
		(exclude_from_sim no)
		(in_bom yes)
		(on_board yes)
		(dnp no)
		(property "Reference" "R227"
			(at 309.88 227.33 90)
			(effects
				(font
					(size 1.27 1.27)
				)
				(justify right)
			)
		)
		(property "Value" "R_2k2_0402"
			(at 321.31 210.82 0)
			(effects
				(font
					(size 1.27 1.27)
					(thickness 0.15)
				)
				(justify left bottom)
				(hide yes)
			)
		)
		(property "Footprint" "antmicro-footprints:R_0402_1005Metric"
			(at 323.85 210.82 0)
			(effects
				(font
					(size 1.27 1.27)
					(thickness 0.15)
				)
				(justify left bottom)
				(hide yes)
			)
		)
		(property "Datasheet" "https://www.bourns.com/docs/product-datasheets/cr.pdf"
			(at 326.39 210.82 0)
			(effects
				(font
					(size 1.27 1.27)
					(thickness 0.15)
				)
				(justify left bottom)
				(hide yes)
			)
		)
		(property "Description" ""
			(at 308.61 231.14 0)
			(effects
				(font
					(size 1.27 1.27)
				)
				(hide yes)
			)
		)
		(property "Manufacturer" "Bourns"
			(at 331.47 210.82 0)
			(effects
				(font
					(size 1.27 1.27)
					(thickness 0.15)
				)
				(justify left bottom)
				(hide yes)
			)
		)
		(property "MPN" "CR0402-FX-2201GLF"
			(at 328.93 210.82 0)
			(effects
				(font
					(size 1.27 1.27)
					(thickness 0.15)
				)
				(justify left bottom)
				(hide yes)
			)
		)
		(property "Val" "2k2"
			(at 309.88 229.87 90)
			(effects
				(font
					(size 1.27 1.27)
					(thickness 0.15)
				)
				(justify right)
			)
		)
		(property "License" "Apache-2.0"
			(at 334.01 210.82 0)
			(effects
				(font
					(size 1.27 1.27)
					(thickness 0.15)
				)
				(justify left bottom)
				(hide yes)
			)
		)
		(property "Author" "Antmicro"
			(at 336.55 210.82 0)
			(effects
				(font
					(size 1.27 1.27)
					(thickness 0.15)
				)
				(justify left bottom)
				(hide yes)
			)
		)
		(property "Tolerance" "1%"
			(at 318.77 210.82 0)
			(effects
				(font
					(size 1.27 1.27)
				)
				(justify left bottom)
				(hide yes)
			)
		)
		(pin "1"
		)
		(pin "2"
		)
		(instances
			(project "jetson-orin-baseboard"
				(path ""
					(reference "R227")
					(unit 1)
				)
			)
		)
	)
	(symbol
		(lib_id "antmicropower:+3V3")
		(at 171.45 203.2 0)
		(unit 1)
		(exclude_from_sim no)
		(in_bom yes)
		(on_board yes)
		(dnp no)
		(property "Reference" "#PWR0300"
			(at 171.45 207.01 0)
			(effects
				(font
					(size 1.27 1.27)
				)
				(justify left bottom)
				(hide yes)
			)
		)
		(property "Value" "+3V3"
			(at 168.275 200.025 0)
			(effects
				(font
					(size 1.27 1.27)
					(thickness 0.15)
				)
				(justify left bottom)
			)
		)
		(property "Footprint" ""
			(at 186.69 210.82 0)
			(effects
				(font
					(size 1.27 1.27)
					(thickness 0.15)
				)
				(justify left bottom)
				(hide yes)
			)
		)
		(property "Datasheet" ""
			(at 186.69 213.36 0)
			(effects
				(font
					(size 1.27 1.27)
					(thickness 0.15)
				)
				(justify left bottom)
				(hide yes)
			)
		)
		(property "Description" ""
			(at 171.45 203.2 0)
			(effects
				(font
					(size 1.27 1.27)
				)
				(hide yes)
			)
		)
		(property "Author" "Antmicro"
			(at 186.69 205.74 0)
			(effects
				(font
					(size 1.27 1.27)
					(thickness 0.15)
				)
				(justify left bottom)
				(hide yes)
			)
		)
		(property "License" "Apache-2.0"
			(at 186.69 208.28 0)
			(effects
				(font
					(size 1.27 1.27)
					(thickness 0.15)
				)
				(justify left bottom)
				(hide yes)
			)
		)
		(pin "1"
		)
		(instances
			(project "jetson-orin-baseboard"
				(path ""
					(reference "#PWR0300")
					(unit 1)
				)
			)
		)
	)
	(symbol
		(lib_id "antmicropower:GND")
		(at 288.29 187.96 0)
		(unit 1)
		(exclude_from_sim no)
		(in_bom yes)
		(on_board yes)
		(dnp no)
		(property "Reference" "#PWR0297"
			(at 288.29 194.31 0)
			(effects
				(font
					(size 1.27 1.27)
				)
				(justify left bottom)
				(hide yes)
			)
		)
		(property "Value" "GND"
			(at 288.29 191.77 0)
			(effects
				(font
					(size 1.27 1.27)
					(thickness 0.15)
				)
			)
		)
		(property "Footprint" ""
			(at 297.18 195.58 0)
			(effects
				(font
					(size 1.27 1.27)
					(thickness 0.15)
				)
				(justify left bottom)
				(hide yes)
			)
		)
		(property "Datasheet" ""
			(at 297.18 200.66 0)
			(effects
				(font
					(size 1.27 1.27)
					(thickness 0.15)
				)
				(justify left bottom)
				(hide yes)
			)
		)
		(property "Description" ""
			(at 288.29 187.96 0)
			(effects
				(font
					(size 1.27 1.27)
				)
				(hide yes)
			)
		)
		(property "Author" "Antmicro"
			(at 297.18 195.58 0)
			(effects
				(font
					(size 1.27 1.27)
					(thickness 0.15)
				)
				(justify left bottom)
				(hide yes)
			)
		)
		(property "License" "Apache-2.0"
			(at 297.18 198.12 0)
			(effects
				(font
					(size 1.27 1.27)
					(thickness 0.15)
				)
				(justify left bottom)
				(hide yes)
			)
		)
		(pin "1"
		)
		(instances
			(project "jetson-orin-baseboard"
				(path ""
					(reference "#PWR0297")
					(unit 1)
				)
			)
		)
	)
	(symbol
		(lib_id "antmicropower:GND")
		(at 182.88 210.82 0)
		(unit 1)
		(exclude_from_sim no)
		(in_bom yes)
		(on_board yes)
		(dnp no)
		(property "Reference" "#PWR0286"
			(at 182.88 217.17 0)
			(effects
				(font
					(size 1.27 1.27)
				)
				(justify left bottom)
				(hide yes)
			)
		)
		(property "Value" "GND"
			(at 182.88 214.63 0)
			(effects
				(font
					(size 1.27 1.27)
					(thickness 0.15)
				)
			)
		)
		(property "Footprint" ""
			(at 191.77 218.44 0)
			(effects
				(font
					(size 1.27 1.27)
					(thickness 0.15)
				)
				(justify left bottom)
				(hide yes)
			)
		)
		(property "Datasheet" ""
			(at 191.77 223.52 0)
			(effects
				(font
					(size 1.27 1.27)
					(thickness 0.15)
				)
				(justify left bottom)
				(hide yes)
			)
		)
		(property "Description" ""
			(at 182.88 210.82 0)
			(effects
				(font
					(size 1.27 1.27)
				)
				(hide yes)
			)
		)
		(property "Author" "Antmicro"
			(at 191.77 218.44 0)
			(effects
				(font
					(size 1.27 1.27)
					(thickness 0.15)
				)
				(justify left bottom)
				(hide yes)
			)
		)
		(property "License" "Apache-2.0"
			(at 191.77 220.98 0)
			(effects
				(font
					(size 1.27 1.27)
					(thickness 0.15)
				)
				(justify left bottom)
				(hide yes)
			)
		)
		(pin "1"
		)
		(instances
			(project "jetson-orin-baseboard"
				(path ""
					(reference "#PWR0286")
					(unit 1)
				)
			)
		)
	)
	(symbol
		(lib_id "antmicroCapacitors0402:C_100n_0402")
		(at 71.12 111.76 0)
		(mirror y)
		(unit 1)
		(exclude_from_sim no)
		(in_bom yes)
		(on_board yes)
		(dnp no)
		(property "Reference" "C131"
			(at 69.85 111.125 0)
			(effects
				(font
					(size 1.27 1.27)
				)
				(justify right bottom)
			)
		)
		(property "Value" "C_100n_0402"
			(at 50.8 121.92 0)
			(effects
				(font
					(size 1.27 1.27)
					(thickness 0.15)
				)
				(justify left bottom)
				(hide yes)
			)
		)
		(property "Footprint" "antmicro-footprints:C_0402_1005Metric"
			(at 50.8 124.46 0)
			(effects
				(font
					(size 1.27 1.27)
					(thickness 0.15)
				)
				(justify left bottom)
				(hide yes)
			)
		)
		(property "Datasheet" "https://www.murata.com/products/productdetail?partno=GRM155R61H104KE14%23"
			(at 50.8 127 0)
			(effects
				(font
					(size 1.27 1.27)
					(thickness 0.15)
				)
				(justify left bottom)
				(hide yes)
			)
		)
		(property "Description" ""
			(at 71.12 111.76 0)
			(effects
				(font
					(size 1.27 1.27)
				)
				(hide yes)
			)
		)
		(property "Manufacturer" "Murata"
			(at 50.8 132.08 0)
			(effects
				(font
					(size 1.27 1.27)
					(thickness 0.15)
				)
				(justify left bottom)
				(hide yes)
			)
		)
		(property "MPN" "GRM155R61H104KE14D"
			(at 50.8 129.54 0)
			(effects
				(font
					(size 1.27 1.27)
					(thickness 0.15)
				)
				(justify left bottom)
				(hide yes)
			)
		)
		(property "Val" "100n"
			(at 67.31 113.665 0)
			(effects
				(font
					(size 1.27 1.27)
					(thickness 0.15)
				)
				(justify left bottom)
			)
		)
		(property "License" "Apache-2.0"
			(at 50.8 134.62 0)
			(effects
				(font
					(size 1.27 1.27)
					(thickness 0.15)
				)
				(justify left bottom)
				(hide yes)
			)
		)
		(property "Author" "Antmicro"
			(at 50.8 137.16 0)
			(effects
				(font
					(size 1.27 1.27)
					(thickness 0.15)
				)
				(justify left bottom)
				(hide yes)
			)
		)
		(property "Voltage" "50V"
			(at 50.8 139.7 0)
			(effects
				(font
					(size 1.27 1.27)
				)
				(justify left bottom)
				(hide yes)
			)
		)
		(property "Dielectric" "X5R"
			(at 50.8 142.24 0)
			(effects
				(font
					(size 1.27 1.27)
				)
				(justify left bottom)
				(hide yes)
			)
		)
		(pin "1"
		)
		(pin "2"
		)
		(instances
			(project "jetson-orin-baseboard"
				(path ""
					(reference "C131")
					(unit 1)
				)
			)
		)
	)
	(symbol
		(lib_id "antmicroCapacitors0402:C_100n_0402")
		(at 152.4 119.38 0)
		(mirror y)
		(unit 1)
		(exclude_from_sim no)
		(in_bom yes)
		(on_board yes)
		(dnp no)
		(property "Reference" "C139"
			(at 151.13 118.745 0)
			(effects
				(font
					(size 1.27 1.27)
				)
				(justify right bottom)
			)
		)
		(property "Value" "C_100n_0402"
			(at 132.08 129.54 0)
			(effects
				(font
					(size 1.27 1.27)
					(thickness 0.15)
				)
				(justify left bottom)
				(hide yes)
			)
		)
		(property "Footprint" "antmicro-footprints:C_0402_1005Metric"
			(at 132.08 132.08 0)
			(effects
				(font
					(size 1.27 1.27)
					(thickness 0.15)
				)
				(justify left bottom)
				(hide yes)
			)
		)
		(property "Datasheet" "https://www.murata.com/products/productdetail?partno=GRM155R61H104KE14%23"
			(at 132.08 134.62 0)
			(effects
				(font
					(size 1.27 1.27)
					(thickness 0.15)
				)
				(justify left bottom)
				(hide yes)
			)
		)
		(property "Description" ""
			(at 152.4 119.38 0)
			(effects
				(font
					(size 1.27 1.27)
				)
				(hide yes)
			)
		)
		(property "Manufacturer" "Murata"
			(at 132.08 139.7 0)
			(effects
				(font
					(size 1.27 1.27)
					(thickness 0.15)
				)
				(justify left bottom)
				(hide yes)
			)
		)
		(property "MPN" "GRM155R61H104KE14D"
			(at 132.08 137.16 0)
			(effects
				(font
					(size 1.27 1.27)
					(thickness 0.15)
				)
				(justify left bottom)
				(hide yes)
			)
		)
		(property "Val" "100n"
			(at 143.51 121.285 0)
			(effects
				(font
					(size 1.27 1.27)
					(thickness 0.15)
				)
				(justify right bottom)
			)
		)
		(property "License" "Apache-2.0"
			(at 132.08 142.24 0)
			(effects
				(font
					(size 1.27 1.27)
					(thickness 0.15)
				)
				(justify left bottom)
				(hide yes)
			)
		)
		(property "Author" "Antmicro"
			(at 132.08 144.78 0)
			(effects
				(font
					(size 1.27 1.27)
					(thickness 0.15)
				)
				(justify left bottom)
				(hide yes)
			)
		)
		(property "Voltage" "50V"
			(at 132.08 147.32 0)
			(effects
				(font
					(size 1.27 1.27)
				)
				(justify left bottom)
				(hide yes)
			)
		)
		(property "Dielectric" "X5R"
			(at 132.08 149.86 0)
			(effects
				(font
					(size 1.27 1.27)
				)
				(justify left bottom)
				(hide yes)
			)
		)
		(pin "1"
		)
		(pin "2"
		)
		(instances
			(project "jetson-orin-baseboard"
				(path ""
					(reference "C139")
					(unit 1)
				)
			)
		)
	)
	(symbol
		(lib_id "antmicroResistors0402:R_499R_0402")
		(at 201.93 185.42 90)
		(unit 1)
		(exclude_from_sim no)
		(in_bom yes)
		(on_board yes)
		(dnp no)
		(property "Reference" "R224"
			(at 203.2 181.61 90)
			(effects
				(font
					(size 1.27 1.27)
					(thickness 0.15)
				)
				(justify right)
			)
		)
		(property "Value" "R_499R_0402"
			(at 214.63 165.1 0)
			(effects
				(font
					(size 1.27 1.27)
					(thickness 0.15)
				)
				(justify left bottom)
				(hide yes)
			)
		)
		(property "Footprint" "antmicro-footprints:R_0402_1005Metric"
			(at 217.17 165.1 0)
			(effects
				(font
					(size 1.27 1.27)
					(thickness 0.15)
				)
				(justify left bottom)
				(hide yes)
			)
		)
		(property "Datasheet" "https://www.mouser.com/datasheet/2/54/cr-1858361.pdf"
			(at 219.71 165.1 0)
			(effects
				(font
					(size 1.27 1.27)
					(thickness 0.15)
				)
				(justify left bottom)
				(hide yes)
			)
		)
		(property "Description" ""
			(at 201.93 185.42 0)
			(effects
				(font
					(size 1.27 1.27)
				)
				(hide yes)
			)
		)
		(property "MPN" "CR0402-FX-4990GLF"
			(at 222.25 165.1 0)
			(effects
				(font
					(size 1.27 1.27)
					(thickness 0.15)
				)
				(justify left bottom)
				(hide yes)
			)
		)
		(property "Manufacturer" "Bourns"
			(at 224.79 165.1 0)
			(effects
				(font
					(size 1.27 1.27)
					(thickness 0.15)
				)
				(justify left bottom)
				(hide yes)
			)
		)
		(property "License" "Apache-2.0"
			(at 227.33 165.1 0)
			(effects
				(font
					(size 1.27 1.27)
					(thickness 0.15)
				)
				(justify left bottom)
				(hide yes)
			)
		)
		(property "Author" "Antmicro"
			(at 229.87 165.1 0)
			(effects
				(font
					(size 1.27 1.27)
					(thickness 0.15)
				)
				(justify left bottom)
				(hide yes)
			)
		)
		(property "Val" "499R"
			(at 203.2 184.15 90)
			(effects
				(font
					(size 1.27 1.27)
					(thickness 0.15)
				)
				(justify right)
			)
		)
		(property "Tolerance" "1%"
			(at 212.09 165.1 0)
			(effects
				(font
					(size 1.27 1.27)
				)
				(justify left bottom)
				(hide yes)
			)
		)
		(pin "1"
		)
		(pin "2"
		)
		(instances
			(project "jetson-orin-baseboard"
				(path ""
					(reference "R224")
					(unit 1)
				)
			)
		)
	)
	(symbol
		(lib_id "antmicroInterfaceAnalogSwitchesSpecialPurpose:TS3DV642RUARQ1")
		(at 99.06 88.9 0)
		(unit 1)
		(exclude_from_sim no)
		(in_bom yes)
		(on_board yes)
		(dnp no)
		(property "Reference" "U36"
			(at 111.76 82.55 0)
			(effects
				(font
					(size 1.27 1.27)
					(thickness 0.15)
				)
			)
		)
		(property "Value" "TS3DV642RUARQ1"
			(at 137.16 96.52 0)
			(effects
				(font
					(size 1.27 1.27)
					(thickness 0.15)
				)
				(justify left bottom)
				(hide yes)
			)
		)
		(property "Footprint" "antmicro-footprints:WQFN-42-1EP_3.5x9mm_P0.5mm"
			(at 137.16 99.06 0)
			(effects
				(font
					(size 1.27 1.27)
					(thickness 0.15)
				)
				(justify left bottom)
				(hide yes)
			)
		)
		(property "Datasheet" "https://www.ti.com/lit/ds/symlink/ts3dv642-q1.pdf?ts=1676983005656&ref_url=https%253A%252F%252Fwww.ti.com%252Fproduct%252FTS3DV642-Q1"
			(at 137.16 101.6 0)
			(effects
				(font
					(size 1.27 1.27)
					(thickness 0.15)
				)
				(justify left bottom)
				(hide yes)
			)
		)
		(property "Description" "Special purpose interface switch"
			(at 99.06 88.9 0)
			(effects
				(font
					(size 1.27 1.27)
				)
				(hide yes)
			)
		)
		(property "MPN" "TS3DV642RUARQ1"
			(at 111.76 85.09 0)
			(effects
				(font
					(size 1.27 1.27)
					(thickness 0.15)
				)
			)
		)
		(property "Manufacturer" "Texas Instruments"
			(at 137.16 106.68 0)
			(effects
				(font
					(size 1.27 1.27)
					(thickness 0.15)
				)
				(justify left bottom)
				(hide yes)
			)
		)
		(property "Author" "Antmicro"
			(at 137.16 109.22 0)
			(effects
				(font
					(size 1.27 1.27)
					(thickness 0.15)
				)
				(justify left bottom)
				(hide yes)
			)
		)
		(property "License" "Apache-2.0"
			(at 137.16 111.76 0)
			(effects
				(font
					(size 1.27 1.27)
					(thickness 0.15)
				)
				(justify left bottom)
				(hide yes)
			)
		)
		(pin "1"
		)
		(pin "10"
		)
		(pin "11"
		)
		(pin "12"
		)
		(pin "13"
		)
		(pin "14"
		)
		(pin "15"
		)
		(pin "16"
		)
		(pin "17"
		)
		(pin "18"
		)
		(pin "19"
		)
		(pin "2"
		)
		(pin "20"
		)
		(pin "21"
		)
		(pin "22"
		)
		(pin "23"
		)
		(pin "24"
		)
		(pin "25"
		)
		(pin "26"
		)
		(pin "27"
		)
		(pin "28"
		)
		(pin "29"
		)
		(pin "3"
		)
		(pin "30"
		)
		(pin "31"
		)
		(pin "32"
		)
		(pin "33"
		)
		(pin "34"
		)
		(pin "35"
		)
		(pin "36"
		)
		(pin "37"
		)
		(pin "38"
		)
		(pin "39"
		)
		(pin "4"
		)
		(pin "40"
		)
		(pin "41"
		)
		(pin "42"
		)
		(pin "43"
		)
		(pin "5"
		)
		(pin "6"
		)
		(pin "7"
		)
		(pin "8"
		)
		(pin "9"
		)
		(instances
			(project "jetson-orin-baseboard"
				(path ""
					(reference "U36")
					(unit 1)
				)
			)
		)
	)
	(symbol
		(lib_id "antmicroResistors0402:R_2k2_0402")
		(at 298.45 176.53 270)
		(mirror x)
		(unit 1)
		(exclude_from_sim no)
		(in_bom no)
		(on_board yes)
		(dnp yes)
		(property "Reference" "R282"
			(at 299.72 172.72 90)
			(effects
				(font
					(size 1.27 1.27)
				)
				(justify left)
			)
		)
		(property "Value" "R_2k2_0402"
			(at 285.75 156.21 0)
			(effects
				(font
					(size 1.27 1.27)
					(thickness 0.15)
				)
				(justify left bottom)
				(hide yes)
			)
		)
		(property "Footprint" "antmicro-footprints:R_0402_1005Metric"
			(at 283.21 156.21 0)
			(effects
				(font
					(size 1.27 1.27)
					(thickness 0.15)
				)
				(justify left bottom)
				(hide yes)
			)
		)
		(property "Datasheet" "https://www.bourns.com/docs/product-datasheets/cr.pdf"
			(at 280.67 156.21 0)
			(effects
				(font
					(size 1.27 1.27)
					(thickness 0.15)
				)
				(justify left bottom)
				(hide yes)
			)
		)
		(property "Description" ""
			(at 298.45 176.53 0)
			(effects
				(font
					(size 1.27 1.27)
				)
				(hide yes)
			)
		)
		(property "Manufacturer" "Bourns"
			(at 275.59 156.21 0)
			(effects
				(font
					(size 1.27 1.27)
					(thickness 0.15)
				)
				(justify left bottom)
				(hide yes)
			)
		)
		(property "MPN" "CR0402-FX-2201GLF"
			(at 278.13 156.21 0)
			(effects
				(font
					(size 1.27 1.27)
					(thickness 0.15)
				)
				(justify left bottom)
				(hide yes)
			)
		)
		(property "Val" "2k2"
			(at 299.72 175.26 90)
			(effects
				(font
					(size 1.27 1.27)
					(thickness 0.15)
				)
				(justify left)
			)
		)
		(property "License" "Apache-2.0"
			(at 273.05 156.21 0)
			(effects
				(font
					(size 1.27 1.27)
					(thickness 0.15)
				)
				(justify left bottom)
				(hide yes)
			)
		)
		(property "Author" "Antmicro"
			(at 270.51 156.21 0)
			(effects
				(font
					(size 1.27 1.27)
					(thickness 0.15)
				)
				(justify left bottom)
				(hide yes)
			)
		)
		(property "Tolerance" "1%"
			(at 288.29 156.21 0)
			(effects
				(font
					(size 1.27 1.27)
				)
				(justify left bottom)
				(hide yes)
			)
		)
		(pin "1"
		)
		(pin "2"
		)
		(instances
			(project "jetson-orin-baseboard"
				(path ""
					(reference "R282")
					(unit 1)
				)
			)
		)
	)
	(symbol
		(lib_id "antmicroResistors0402:R_499R_0402")
		(at 171.45 185.42 90)
		(unit 1)
		(exclude_from_sim no)
		(in_bom yes)
		(on_board yes)
		(dnp no)
		(property "Reference" "R213"
			(at 172.72 181.61 90)
			(effects
				(font
					(size 1.27 1.27)
					(thickness 0.15)
				)
				(justify right)
			)
		)
		(property "Value" "R_499R_0402"
			(at 184.15 165.1 0)
			(effects
				(font
					(size 1.27 1.27)
					(thickness 0.15)
				)
				(justify left bottom)
				(hide yes)
			)
		)
		(property "Footprint" "antmicro-footprints:R_0402_1005Metric"
			(at 186.69 165.1 0)
			(effects
				(font
					(size 1.27 1.27)
					(thickness 0.15)
				)
				(justify left bottom)
				(hide yes)
			)
		)
		(property "Datasheet" "https://www.mouser.com/datasheet/2/54/cr-1858361.pdf"
			(at 189.23 165.1 0)
			(effects
				(font
					(size 1.27 1.27)
					(thickness 0.15)
				)
				(justify left bottom)
				(hide yes)
			)
		)
		(property "Description" ""
			(at 171.45 185.42 0)
			(effects
				(font
					(size 1.27 1.27)
				)
				(hide yes)
			)
		)
		(property "MPN" "CR0402-FX-4990GLF"
			(at 191.77 165.1 0)
			(effects
				(font
					(size 1.27 1.27)
					(thickness 0.15)
				)
				(justify left bottom)
				(hide yes)
			)
		)
		(property "Manufacturer" "Bourns"
			(at 194.31 165.1 0)
			(effects
				(font
					(size 1.27 1.27)
					(thickness 0.15)
				)
				(justify left bottom)
				(hide yes)
			)
		)
		(property "License" "Apache-2.0"
			(at 196.85 165.1 0)
			(effects
				(font
					(size 1.27 1.27)
					(thickness 0.15)
				)
				(justify left bottom)
				(hide yes)
			)
		)
		(property "Author" "Antmicro"
			(at 199.39 165.1 0)
			(effects
				(font
					(size 1.27 1.27)
					(thickness 0.15)
				)
				(justify left bottom)
				(hide yes)
			)
		)
		(property "Val" "499R"
			(at 172.72 184.15 90)
			(effects
				(font
					(size 1.27 1.27)
					(thickness 0.15)
				)
				(justify right)
			)
		)
		(property "Tolerance" "1%"
			(at 181.61 165.1 0)
			(effects
				(font
					(size 1.27 1.27)
				)
				(justify left bottom)
				(hide yes)
			)
		)
		(pin "1"
		)
		(pin "2"
		)
		(instances
			(project "jetson-orin-baseboard"
				(path ""
					(reference "R213")
					(unit 1)
				)
			)
		)
	)
	(symbol
		(lib_id "antmicropower:GND")
		(at 269.24 228.6 0)
		(unit 1)
		(exclude_from_sim no)
		(in_bom yes)
		(on_board yes)
		(dnp no)
		(property "Reference" "#PWR0301"
			(at 269.24 234.95 0)
			(effects
				(font
					(size 1.27 1.27)
				)
				(justify left bottom)
				(hide yes)
			)
		)
		(property "Value" "GND"
			(at 269.24 232.41 0)
			(effects
				(font
					(size 1.27 1.27)
					(thickness 0.15)
				)
			)
		)
		(property "Footprint" ""
			(at 278.13 236.22 0)
			(effects
				(font
					(size 1.27 1.27)
					(thickness 0.15)
				)
				(justify left bottom)
				(hide yes)
			)
		)
		(property "Datasheet" ""
			(at 278.13 241.3 0)
			(effects
				(font
					(size 1.27 1.27)
					(thickness 0.15)
				)
				(justify left bottom)
				(hide yes)
			)
		)
		(property "Description" ""
			(at 269.24 228.6 0)
			(effects
				(font
					(size 1.27 1.27)
				)
				(hide yes)
			)
		)
		(property "Author" "Antmicro"
			(at 278.13 236.22 0)
			(effects
				(font
					(size 1.27 1.27)
					(thickness 0.15)
				)
				(justify left bottom)
				(hide yes)
			)
		)
		(property "License" "Apache-2.0"
			(at 278.13 238.76 0)
			(effects
				(font
					(size 1.27 1.27)
					(thickness 0.15)
				)
				(justify left bottom)
				(hide yes)
			)
		)
		(pin "1"
		)
		(instances
			(project "jetson-orin-baseboard"
				(path ""
					(reference "#PWR0301")
					(unit 1)
				)
			)
		)
	)
	(symbol
		(lib_id "antmicroTransistorsFETsMOSFETsSingle:PJE138K")
		(at 69.85 198.12 0)
		(unit 1)
		(exclude_from_sim no)
		(in_bom no)
		(on_board yes)
		(dnp yes)
		(property "Reference" "Q3"
			(at 78.74 193.04 0)
			(effects
				(font
					(size 1.27 1.27)
					(thickness 0.15)
				)
				(justify left)
			)
		)
		(property "Value" "PJE138K"
			(at 92.71 207.01 0)
			(effects
				(font
					(size 1.27 1.27)
					(thickness 0.15)
				)
				(justify left bottom)
				(hide yes)
			)
		)
		(property "Footprint" "antmicro-footprints:SOT-523"
			(at 92.71 209.55 0)
			(effects
				(font
					(size 1.27 1.27)
					(thickness 0.15)
				)
				(justify left bottom)
				(hide yes)
			)
		)
		(property "Datasheet" "https://www.mouser.com/datasheet/2/1057/PJE138K-1876698.pdf"
			(at 92.71 212.09 0)
			(effects
				(font
					(size 1.27 1.27)
					(thickness 0.15)
				)
				(justify left bottom)
				(hide yes)
			)
		)
		(property "Description" ""
			(at 69.85 198.12 0)
			(effects
				(font
					(size 1.27 1.27)
				)
				(hide yes)
			)
		)
		(property "MPN" "PJE138K_R1_00001"
			(at 78.74 195.58 0)
			(effects
				(font
					(size 1.27 1.27)
					(thickness 0.15)
				)
				(justify left)
			)
		)
		(property "Manufacturer" "PANJIT"
			(at 92.71 217.17 0)
			(effects
				(font
					(size 1.27 1.27)
					(thickness 0.15)
				)
				(justify left bottom)
				(hide yes)
			)
		)
		(property "Author" "Antmicro"
			(at 92.71 219.71 0)
			(effects
				(font
					(size 1.27 1.27)
					(thickness 0.15)
				)
				(justify left bottom)
				(hide yes)
			)
		)
		(property "License" "Apache-2.0"
			(at 92.71 222.25 0)
			(effects
				(font
					(size 1.27 1.27)
					(thickness 0.15)
				)
				(justify left bottom)
				(hide yes)
			)
		)
		(pin "2"
		)
		(pin "3"
		)
		(pin "1"
		)
		(instances
			(project "jetson-orin-baseboard"
				(path ""
					(reference "Q3")
					(unit 1)
				)
			)
		)
	)
	(symbol
		(lib_id "antmicroResistors0402:R_499R_0402")
		(at 179.07 190.5 90)
		(unit 1)
		(exclude_from_sim no)
		(in_bom yes)
		(on_board yes)
		(dnp no)
		(property "Reference" "R214"
			(at 180.34 186.69 90)
			(effects
				(font
					(size 1.27 1.27)
					(thickness 0.15)
				)
				(justify right)
			)
		)
		(property "Value" "R_499R_0402"
			(at 191.77 170.18 0)
			(effects
				(font
					(size 1.27 1.27)
					(thickness 0.15)
				)
				(justify left bottom)
				(hide yes)
			)
		)
		(property "Footprint" "antmicro-footprints:R_0402_1005Metric"
			(at 194.31 170.18 0)
			(effects
				(font
					(size 1.27 1.27)
					(thickness 0.15)
				)
				(justify left bottom)
				(hide yes)
			)
		)
		(property "Datasheet" "https://www.mouser.com/datasheet/2/54/cr-1858361.pdf"
			(at 196.85 170.18 0)
			(effects
				(font
					(size 1.27 1.27)
					(thickness 0.15)
				)
				(justify left bottom)
				(hide yes)
			)
		)
		(property "Description" ""
			(at 179.07 190.5 0)
			(effects
				(font
					(size 1.27 1.27)
				)
				(hide yes)
			)
		)
		(property "MPN" "CR0402-FX-4990GLF"
			(at 199.39 170.18 0)
			(effects
				(font
					(size 1.27 1.27)
					(thickness 0.15)
				)
				(justify left bottom)
				(hide yes)
			)
		)
		(property "Manufacturer" "Bourns"
			(at 201.93 170.18 0)
			(effects
				(font
					(size 1.27 1.27)
					(thickness 0.15)
				)
				(justify left bottom)
				(hide yes)
			)
		)
		(property "License" "Apache-2.0"
			(at 204.47 170.18 0)
			(effects
				(font
					(size 1.27 1.27)
					(thickness 0.15)
				)
				(justify left bottom)
				(hide yes)
			)
		)
		(property "Author" "Antmicro"
			(at 207.01 170.18 0)
			(effects
				(font
					(size 1.27 1.27)
					(thickness 0.15)
				)
				(justify left bottom)
				(hide yes)
			)
		)
		(property "Val" "499R"
			(at 180.34 189.23 90)
			(effects
				(font
					(size 1.27 1.27)
					(thickness 0.15)
				)
				(justify right)
			)
		)
		(property "Tolerance" "1%"
			(at 189.23 170.18 0)
			(effects
				(font
					(size 1.27 1.27)
				)
				(justify left bottom)
				(hide yes)
			)
		)
		(pin "1"
		)
		(pin "2"
		)
		(instances
			(project "jetson-orin-baseboard"
				(path ""
					(reference "R214")
					(unit 1)
				)
			)
		)
	)
	(symbol
		(lib_id "antmicropower:GND")
		(at 308.61 232.41 0)
		(unit 1)
		(exclude_from_sim no)
		(in_bom yes)
		(on_board yes)
		(dnp no)
		(property "Reference" "#PWR0305"
			(at 308.61 238.76 0)
			(effects
				(font
					(size 1.27 1.27)
				)
				(justify left bottom)
				(hide yes)
			)
		)
		(property "Value" "GND"
			(at 308.61 236.22 0)
			(effects
				(font
					(size 1.27 1.27)
					(thickness 0.15)
				)
			)
		)
		(property "Footprint" ""
			(at 317.5 240.03 0)
			(effects
				(font
					(size 1.27 1.27)
					(thickness 0.15)
				)
				(justify left bottom)
				(hide yes)
			)
		)
		(property "Datasheet" ""
			(at 317.5 245.11 0)
			(effects
				(font
					(size 1.27 1.27)
					(thickness 0.15)
				)
				(justify left bottom)
				(hide yes)
			)
		)
		(property "Description" ""
			(at 308.61 232.41 0)
			(effects
				(font
					(size 1.27 1.27)
				)
				(hide yes)
			)
		)
		(property "Author" "Antmicro"
			(at 317.5 240.03 0)
			(effects
				(font
					(size 1.27 1.27)
					(thickness 0.15)
				)
				(justify left bottom)
				(hide yes)
			)
		)
		(property "License" "Apache-2.0"
			(at 317.5 242.57 0)
			(effects
				(font
					(size 1.27 1.27)
					(thickness 0.15)
				)
				(justify left bottom)
				(hide yes)
			)
		)
		(pin "1"
		)
		(instances
			(project "jetson-orin-baseboard"
				(path ""
					(reference "#PWR0305")
					(unit 1)
				)
			)
		)
	)
	(symbol
		(lib_id "antmicroResistors0402:R_499R_0402")
		(at 146.05 190.5 90)
		(unit 1)
		(exclude_from_sim no)
		(in_bom yes)
		(on_board yes)
		(dnp no)
		(property "Reference" "R209"
			(at 147.32 186.69 90)
			(effects
				(font
					(size 1.27 1.27)
					(thickness 0.15)
				)
				(justify right)
			)
		)
		(property "Value" "R_499R_0402"
			(at 158.75 170.18 0)
			(effects
				(font
					(size 1.27 1.27)
					(thickness 0.15)
				)
				(justify left bottom)
				(hide yes)
			)
		)
		(property "Footprint" "antmicro-footprints:R_0402_1005Metric"
			(at 161.29 170.18 0)
			(effects
				(font
					(size 1.27 1.27)
					(thickness 0.15)
				)
				(justify left bottom)
				(hide yes)
			)
		)
		(property "Datasheet" "https://www.mouser.com/datasheet/2/54/cr-1858361.pdf"
			(at 163.83 170.18 0)
			(effects
				(font
					(size 1.27 1.27)
					(thickness 0.15)
				)
				(justify left bottom)
				(hide yes)
			)
		)
		(property "Description" ""
			(at 146.05 190.5 0)
			(effects
				(font
					(size 1.27 1.27)
				)
				(hide yes)
			)
		)
		(property "MPN" "CR0402-FX-4990GLF"
			(at 166.37 170.18 0)
			(effects
				(font
					(size 1.27 1.27)
					(thickness 0.15)
				)
				(justify left bottom)
				(hide yes)
			)
		)
		(property "Manufacturer" "Bourns"
			(at 168.91 170.18 0)
			(effects
				(font
					(size 1.27 1.27)
					(thickness 0.15)
				)
				(justify left bottom)
				(hide yes)
			)
		)
		(property "License" "Apache-2.0"
			(at 171.45 170.18 0)
			(effects
				(font
					(size 1.27 1.27)
					(thickness 0.15)
				)
				(justify left bottom)
				(hide yes)
			)
		)
		(property "Author" "Antmicro"
			(at 173.99 170.18 0)
			(effects
				(font
					(size 1.27 1.27)
					(thickness 0.15)
				)
				(justify left bottom)
				(hide yes)
			)
		)
		(property "Val" "499R"
			(at 147.32 189.23 90)
			(effects
				(font
					(size 1.27 1.27)
					(thickness 0.15)
				)
				(justify right)
			)
		)
		(property "Tolerance" "1%"
			(at 156.21 170.18 0)
			(effects
				(font
					(size 1.27 1.27)
				)
				(justify left bottom)
				(hide yes)
			)
		)
		(pin "1"
		)
		(pin "2"
		)
		(instances
			(project "jetson-orin-baseboard"
				(path ""
					(reference "R209")
					(unit 1)
				)
			)
		)
	)
	(symbol
		(lib_id "antmicroResistors0402:R_0R_0402")
		(at 295.91 224.79 0)
		(unit 1)
		(exclude_from_sim no)
		(in_bom no)
		(on_board yes)
		(dnp yes)
		(property "Reference" "R293"
			(at 300.99 224.155 0)
			(effects
				(font
					(size 1.27 1.27)
				)
				(justify left bottom)
			)
		)
		(property "Value" "R_0R_0402"
			(at 316.23 237.49 0)
			(effects
				(font
					(size 1.27 1.27)
					(thickness 0.15)
				)
				(justify left bottom)
				(hide yes)
			)
		)
		(property "Footprint" "antmicro-footprints:R_0402_1005Metric"
			(at 316.23 240.03 0)
			(effects
				(font
					(size 1.27 1.27)
					(thickness 0.15)
				)
				(justify left bottom)
				(hide yes)
			)
		)
		(property "Datasheet" "https://industrial.panasonic.com/cdbs/www-data/pdf/RDA0000/AOA0000C301.pdf"
			(at 316.23 242.57 0)
			(effects
				(font
					(size 1.27 1.27)
					(thickness 0.15)
				)
				(justify left bottom)
				(hide yes)
			)
		)
		(property "Description" ""
			(at 295.91 224.79 0)
			(effects
				(font
					(size 1.27 1.27)
				)
				(hide yes)
			)
		)
		(property "Manufacturer" "Panasonic"
			(at 316.23 247.65 0)
			(effects
				(font
					(size 1.27 1.27)
					(thickness 0.15)
				)
				(justify left bottom)
				(hide yes)
			)
		)
		(property "MPN" "ERJ2GE0R00X"
			(at 316.23 245.11 0)
			(effects
				(font
					(size 1.27 1.27)
					(thickness 0.15)
				)
				(justify left bottom)
				(hide yes)
			)
		)
		(property "Val" "0R"
			(at 293.37 224.155 0)
			(effects
				(font
					(size 1.27 1.27)
					(thickness 0.15)
				)
				(justify left bottom)
			)
		)
		(property "License" "Apache-2.0"
			(at 316.23 250.19 0)
			(effects
				(font
					(size 1.27 1.27)
					(thickness 0.15)
				)
				(justify left bottom)
				(hide yes)
			)
		)
		(property "Author" "Antmicro"
			(at 316.23 252.73 0)
			(effects
				(font
					(size 1.27 1.27)
					(thickness 0.15)
				)
				(justify left bottom)
				(hide yes)
			)
		)
		(property "Tolerance" "~"
			(at 316.23 234.95 0)
			(effects
				(font
					(size 1.27 1.27)
				)
				(justify left bottom)
				(hide yes)
			)
		)
		(property "Current" "1A"
			(at 316.23 255.27 0)
			(effects
				(font
					(size 1.27 1.27)
					(thickness 0.15)
				)
				(justify left bottom)
				(hide yes)
			)
		)
		(pin "1"
		)
		(pin "2"
		)
		(instances
			(project "jetson-orin-baseboard"
				(path ""
					(reference "R293")
					(unit 1)
				)
			)
		)
	)
	(symbol
		(lib_id "antmicropower:PWR_FLAG")
		(at 339.09 186.69 0)
		(unit 1)
		(exclude_from_sim no)
		(in_bom yes)
		(on_board yes)
		(dnp no)
		(property "Reference" "#FLG08"
			(at 339.09 184.785 0)
			(effects
				(font
					(size 1.27 1.27)
				)
				(hide yes)
			)
		)
		(property "Value" "PWR_FLAG"
			(at 339.09 182.88 0)
			(effects
				(font
					(size 1.27 1.27)
				)
			)
		)
		(property "Footprint" ""
			(at 339.09 186.69 0)
			(effects
				(font
					(size 1.27 1.27)
				)
				(hide yes)
			)
		)
		(property "Datasheet" ""
			(at 339.09 186.69 0)
			(effects
				(font
					(size 1.27 1.27)
				)
				(hide yes)
			)
		)
		(property "Description" ""
			(at 339.09 186.69 0)
			(effects
				(font
					(size 1.27 1.27)
				)
				(hide yes)
			)
		)
		(pin "1"
		)
		(instances
			(project "jetson-orin-baseboard"
				(path ""
					(reference "#FLG08")
					(unit 1)
				)
			)
		)
	)
	(symbol
		(lib_id "antmicropower:GND")
		(at 260.35 199.39 0)
		(unit 1)
		(exclude_from_sim no)
		(in_bom yes)
		(on_board yes)
		(dnp no)
		(property "Reference" "#PWR0296"
			(at 260.35 205.74 0)
			(effects
				(font
					(size 1.27 1.27)
				)
				(justify left bottom)
				(hide yes)
			)
		)
		(property "Value" "GND"
			(at 260.35 203.2 0)
			(effects
				(font
					(size 1.27 1.27)
					(thickness 0.15)
				)
			)
		)
		(property "Footprint" ""
			(at 269.24 207.01 0)
			(effects
				(font
					(size 1.27 1.27)
					(thickness 0.15)
				)
				(justify left bottom)
				(hide yes)
			)
		)
		(property "Datasheet" ""
			(at 269.24 212.09 0)
			(effects
				(font
					(size 1.27 1.27)
					(thickness 0.15)
				)
				(justify left bottom)
				(hide yes)
			)
		)
		(property "Description" ""
			(at 260.35 199.39 0)
			(effects
				(font
					(size 1.27 1.27)
				)
				(hide yes)
			)
		)
		(property "Author" "Antmicro"
			(at 269.24 207.01 0)
			(effects
				(font
					(size 1.27 1.27)
					(thickness 0.15)
				)
				(justify left bottom)
				(hide yes)
			)
		)
		(property "License" "Apache-2.0"
			(at 269.24 209.55 0)
			(effects
				(font
					(size 1.27 1.27)
					(thickness 0.15)
				)
				(justify left bottom)
				(hide yes)
			)
		)
		(pin "1"
		)
		(instances
			(project "jetson-orin-baseboard"
				(path ""
					(reference "#PWR0296")
					(unit 1)
				)
			)
		)
	)
	(symbol
		(lib_id "antmicroCapacitors0402:C_100n_0402")
		(at 156.21 121.92 0)
		(mirror y)
		(unit 1)
		(exclude_from_sim no)
		(in_bom yes)
		(on_board yes)
		(dnp no)
		(property "Reference" "C138"
			(at 154.94 121.285 0)
			(effects
				(font
					(size 1.27 1.27)
				)
				(justify right bottom)
			)
		)
		(property "Value" "C_100n_0402"
			(at 135.89 132.08 0)
			(effects
				(font
					(size 1.27 1.27)
					(thickness 0.15)
				)
				(justify left bottom)
				(hide yes)
			)
		)
		(property "Footprint" "antmicro-footprints:C_0402_1005Metric"
			(at 135.89 134.62 0)
			(effects
				(font
					(size 1.27 1.27)
					(thickness 0.15)
				)
				(justify left bottom)
				(hide yes)
			)
		)
		(property "Datasheet" "https://www.murata.com/products/productdetail?partno=GRM155R61H104KE14%23"
			(at 135.89 137.16 0)
			(effects
				(font
					(size 1.27 1.27)
					(thickness 0.15)
				)
				(justify left bottom)
				(hide yes)
			)
		)
		(property "Description" ""
			(at 156.21 121.92 0)
			(effects
				(font
					(size 1.27 1.27)
				)
				(hide yes)
			)
		)
		(property "Manufacturer" "Murata"
			(at 135.89 142.24 0)
			(effects
				(font
					(size 1.27 1.27)
					(thickness 0.15)
				)
				(justify left bottom)
				(hide yes)
			)
		)
		(property "MPN" "GRM155R61H104KE14D"
			(at 135.89 139.7 0)
			(effects
				(font
					(size 1.27 1.27)
					(thickness 0.15)
				)
				(justify left bottom)
				(hide yes)
			)
		)
		(property "Val" "100n"
			(at 147.32 123.825 0)
			(effects
				(font
					(size 1.27 1.27)
					(thickness 0.15)
				)
				(justify right bottom)
			)
		)
		(property "License" "Apache-2.0"
			(at 135.89 144.78 0)
			(effects
				(font
					(size 1.27 1.27)
					(thickness 0.15)
				)
				(justify left bottom)
				(hide yes)
			)
		)
		(property "Author" "Antmicro"
			(at 135.89 147.32 0)
			(effects
				(font
					(size 1.27 1.27)
					(thickness 0.15)
				)
				(justify left bottom)
				(hide yes)
			)
		)
		(property "Voltage" "50V"
			(at 135.89 149.86 0)
			(effects
				(font
					(size 1.27 1.27)
				)
				(justify left bottom)
				(hide yes)
			)
		)
		(property "Dielectric" "X5R"
			(at 135.89 152.4 0)
			(effects
				(font
					(size 1.27 1.27)
				)
				(justify left bottom)
				(hide yes)
			)
		)
		(pin "1"
		)
		(pin "2"
		)
		(instances
			(project "jetson-orin-baseboard"
				(path ""
					(reference "C138")
					(unit 1)
				)
			)
		)
	)
	(symbol
		(lib_id "antmicropower:+3V3")
		(at 87.63 158.75 0)
		(unit 1)
		(exclude_from_sim no)
		(in_bom yes)
		(on_board yes)
		(dnp no)
		(property "Reference" "#PWR0304"
			(at 87.63 162.56 0)
			(effects
				(font
					(size 1.27 1.27)
				)
				(justify left bottom)
				(hide yes)
			)
		)
		(property "Value" "+3V3"
			(at 84.455 155.575 0)
			(effects
				(font
					(size 1.27 1.27)
					(thickness 0.15)
				)
				(justify left bottom)
			)
		)
		(property "Footprint" ""
			(at 102.87 166.37 0)
			(effects
				(font
					(size 1.27 1.27)
					(thickness 0.15)
				)
				(justify left bottom)
				(hide yes)
			)
		)
		(property "Datasheet" ""
			(at 102.87 168.91 0)
			(effects
				(font
					(size 1.27 1.27)
					(thickness 0.15)
				)
				(justify left bottom)
				(hide yes)
			)
		)
		(property "Description" ""
			(at 87.63 158.75 0)
			(effects
				(font
					(size 1.27 1.27)
				)
				(hide yes)
			)
		)
		(property "Author" "Antmicro"
			(at 102.87 161.29 0)
			(effects
				(font
					(size 1.27 1.27)
					(thickness 0.15)
				)
				(justify left bottom)
				(hide yes)
			)
		)
		(property "License" "Apache-2.0"
			(at 102.87 163.83 0)
			(effects
				(font
					(size 1.27 1.27)
					(thickness 0.15)
				)
				(justify left bottom)
				(hide yes)
			)
		)
		(pin "1"
		)
		(instances
			(project "jetson-orin-baseboard"
				(path ""
					(reference "#PWR0304")
					(unit 1)
				)
			)
		)
	)
	(symbol
		(lib_id "antmicroResistors0402:R_499R_0402")
		(at 194.31 190.5 90)
		(unit 1)
		(exclude_from_sim no)
		(in_bom yes)
		(on_board yes)
		(dnp no)
		(property "Reference" "R221"
			(at 195.58 186.69 90)
			(effects
				(font
					(size 1.27 1.27)
					(thickness 0.15)
				)
				(justify right)
			)
		)
		(property "Value" "R_499R_0402"
			(at 207.01 170.18 0)
			(effects
				(font
					(size 1.27 1.27)
					(thickness 0.15)
				)
				(justify left bottom)
				(hide yes)
			)
		)
		(property "Footprint" "antmicro-footprints:R_0402_1005Metric"
			(at 209.55 170.18 0)
			(effects
				(font
					(size 1.27 1.27)
					(thickness 0.15)
				)
				(justify left bottom)
				(hide yes)
			)
		)
		(property "Datasheet" "https://www.mouser.com/datasheet/2/54/cr-1858361.pdf"
			(at 212.09 170.18 0)
			(effects
				(font
					(size 1.27 1.27)
					(thickness 0.15)
				)
				(justify left bottom)
				(hide yes)
			)
		)
		(property "Description" ""
			(at 194.31 190.5 0)
			(effects
				(font
					(size 1.27 1.27)
				)
				(hide yes)
			)
		)
		(property "MPN" "CR0402-FX-4990GLF"
			(at 214.63 170.18 0)
			(effects
				(font
					(size 1.27 1.27)
					(thickness 0.15)
				)
				(justify left bottom)
				(hide yes)
			)
		)
		(property "Manufacturer" "Bourns"
			(at 217.17 170.18 0)
			(effects
				(font
					(size 1.27 1.27)
					(thickness 0.15)
				)
				(justify left bottom)
				(hide yes)
			)
		)
		(property "License" "Apache-2.0"
			(at 219.71 170.18 0)
			(effects
				(font
					(size 1.27 1.27)
					(thickness 0.15)
				)
				(justify left bottom)
				(hide yes)
			)
		)
		(property "Author" "Antmicro"
			(at 222.25 170.18 0)
			(effects
				(font
					(size 1.27 1.27)
					(thickness 0.15)
				)
				(justify left bottom)
				(hide yes)
			)
		)
		(property "Val" "499R"
			(at 195.58 189.23 90)
			(effects
				(font
					(size 1.27 1.27)
					(thickness 0.15)
				)
				(justify right)
			)
		)
		(property "Tolerance" "1%"
			(at 204.47 170.18 0)
			(effects
				(font
					(size 1.27 1.27)
				)
				(justify left bottom)
				(hide yes)
			)
		)
		(pin "1"
		)
		(pin "2"
		)
		(instances
			(project "jetson-orin-baseboard"
				(path ""
					(reference "R221")
					(unit 1)
				)
			)
		)
	)
	(symbol
		(lib_id "antmicroResistors0402:R_2k2_0402")
		(at 294.64 176.53 90)
		(unit 1)
		(exclude_from_sim no)
		(in_bom no)
		(on_board yes)
		(dnp yes)
		(property "Reference" "R281"
			(at 293.37 172.72 90)
			(effects
				(font
					(size 1.27 1.27)
				)
				(justify left)
			)
		)
		(property "Value" "R_2k2_0402"
			(at 307.34 156.21 0)
			(effects
				(font
					(size 1.27 1.27)
					(thickness 0.15)
				)
				(justify left bottom)
				(hide yes)
			)
		)
		(property "Footprint" "antmicro-footprints:R_0402_1005Metric"
			(at 309.88 156.21 0)
			(effects
				(font
					(size 1.27 1.27)
					(thickness 0.15)
				)
				(justify left bottom)
				(hide yes)
			)
		)
		(property "Datasheet" "https://www.bourns.com/docs/product-datasheets/cr.pdf"
			(at 312.42 156.21 0)
			(effects
				(font
					(size 1.27 1.27)
					(thickness 0.15)
				)
				(justify left bottom)
				(hide yes)
			)
		)
		(property "Description" ""
			(at 294.64 176.53 0)
			(effects
				(font
					(size 1.27 1.27)
				)
				(hide yes)
			)
		)
		(property "Manufacturer" "Bourns"
			(at 317.5 156.21 0)
			(effects
				(font
					(size 1.27 1.27)
					(thickness 0.15)
				)
				(justify left bottom)
				(hide yes)
			)
		)
		(property "MPN" "CR0402-FX-2201GLF"
			(at 314.96 156.21 0)
			(effects
				(font
					(size 1.27 1.27)
					(thickness 0.15)
				)
				(justify left bottom)
				(hide yes)
			)
		)
		(property "Val" "2k2"
			(at 293.37 175.26 90)
			(effects
				(font
					(size 1.27 1.27)
					(thickness 0.15)
				)
				(justify left)
			)
		)
		(property "License" "Apache-2.0"
			(at 320.04 156.21 0)
			(effects
				(font
					(size 1.27 1.27)
					(thickness 0.15)
				)
				(justify left bottom)
				(hide yes)
			)
		)
		(property "Author" "Antmicro"
			(at 322.58 156.21 0)
			(effects
				(font
					(size 1.27 1.27)
					(thickness 0.15)
				)
				(justify left bottom)
				(hide yes)
			)
		)
		(property "Tolerance" "1%"
			(at 304.8 156.21 0)
			(effects
				(font
					(size 1.27 1.27)
				)
				(justify left bottom)
				(hide yes)
			)
		)
		(pin "1"
		)
		(pin "2"
		)
		(instances
			(project "jetson-orin-baseboard"
				(path ""
					(reference "R281")
					(unit 1)
				)
			)
		)
	)
	(symbol
		(lib_id "antmicropower:+5V")
		(at 313.69 186.69 0)
		(unit 1)
		(exclude_from_sim no)
		(in_bom yes)
		(on_board yes)
		(dnp no)
		(property "Reference" "#PWR0299"
			(at 313.69 190.5 0)
			(effects
				(font
					(size 1.27 1.27)
				)
				(justify left bottom)
				(hide yes)
			)
		)
		(property "Value" "+5V"
			(at 311.785 183.515 0)
			(effects
				(font
					(size 1.27 1.27)
					(thickness 0.15)
				)
				(justify left bottom)
			)
		)
		(property "Footprint" ""
			(at 328.93 194.31 0)
			(effects
				(font
					(size 1.27 1.27)
					(thickness 0.15)
				)
				(justify left bottom)
				(hide yes)
			)
		)
		(property "Datasheet" ""
			(at 328.93 196.85 0)
			(effects
				(font
					(size 1.27 1.27)
					(thickness 0.15)
				)
				(justify left bottom)
				(hide yes)
			)
		)
		(property "Description" ""
			(at 313.69 186.69 0)
			(effects
				(font
					(size 1.27 1.27)
				)
				(hide yes)
			)
		)
		(property "Author" "Antmicro"
			(at 328.93 194.31 0)
			(effects
				(font
					(size 1.27 1.27)
					(thickness 0.15)
				)
				(justify left bottom)
				(hide yes)
			)
		)
		(property "License" "Apache-2.0"
			(at 328.93 196.85 0)
			(effects
				(font
					(size 1.27 1.27)
					(thickness 0.15)
				)
				(justify left bottom)
				(hide yes)
			)
		)
		(pin "1"
		)
		(instances
			(project "jetson-orin-baseboard"
				(path ""
					(reference "#PWR0299")
					(unit 1)
				)
			)
		)
	)
	(symbol
		(lib_id "antmicropower:+3V3")
		(at 256.54 172.72 0)
		(unit 1)
		(exclude_from_sim no)
		(in_bom yes)
		(on_board yes)
		(dnp no)
		(property "Reference" "#PWR0294"
			(at 256.54 176.53 0)
			(effects
				(font
					(size 1.27 1.27)
				)
				(justify left bottom)
				(hide yes)
			)
		)
		(property "Value" "+3V3"
			(at 253.365 168.91 0)
			(effects
				(font
					(size 1.27 1.27)
					(thickness 0.15)
				)
				(justify left)
			)
		)
		(property "Footprint" ""
			(at 271.78 180.34 0)
			(effects
				(font
					(size 1.27 1.27)
					(thickness 0.15)
				)
				(justify left bottom)
				(hide yes)
			)
		)
		(property "Datasheet" ""
			(at 271.78 182.88 0)
			(effects
				(font
					(size 1.27 1.27)
					(thickness 0.15)
				)
				(justify left bottom)
				(hide yes)
			)
		)
		(property "Description" ""
			(at 256.54 172.72 0)
			(effects
				(font
					(size 1.27 1.27)
				)
				(hide yes)
			)
		)
		(property "Author" "Antmicro"
			(at 271.78 175.26 0)
			(effects
				(font
					(size 1.27 1.27)
					(thickness 0.15)
				)
				(justify left bottom)
				(hide yes)
			)
		)
		(property "License" "Apache-2.0"
			(at 271.78 177.8 0)
			(effects
				(font
					(size 1.27 1.27)
					(thickness 0.15)
				)
				(justify left bottom)
				(hide yes)
			)
		)
		(pin "1"
		)
		(instances
			(project "jetson-orin-baseboard"
				(path ""
					(reference "#PWR0294")
					(unit 1)
				)
			)
		)
	)
	(symbol
		(lib_id "antmicroCapacitors0402:C_100n_0402")
		(at 71.12 137.16 0)
		(mirror y)
		(unit 1)
		(exclude_from_sim no)
		(in_bom yes)
		(on_board yes)
		(dnp no)
		(property "Reference" "C135"
			(at 69.85 136.525 0)
			(effects
				(font
					(size 1.27 1.27)
				)
				(justify right bottom)
			)
		)
		(property "Value" "C_100n_0402"
			(at 50.8 147.32 0)
			(effects
				(font
					(size 1.27 1.27)
					(thickness 0.15)
				)
				(justify left bottom)
				(hide yes)
			)
		)
		(property "Footprint" "antmicro-footprints:C_0402_1005Metric"
			(at 50.8 149.86 0)
			(effects
				(font
					(size 1.27 1.27)
					(thickness 0.15)
				)
				(justify left bottom)
				(hide yes)
			)
		)
		(property "Datasheet" "https://www.murata.com/products/productdetail?partno=GRM155R61H104KE14%23"
			(at 50.8 152.4 0)
			(effects
				(font
					(size 1.27 1.27)
					(thickness 0.15)
				)
				(justify left bottom)
				(hide yes)
			)
		)
		(property "Description" ""
			(at 71.12 137.16 0)
			(effects
				(font
					(size 1.27 1.27)
				)
				(hide yes)
			)
		)
		(property "Manufacturer" "Murata"
			(at 50.8 157.48 0)
			(effects
				(font
					(size 1.27 1.27)
					(thickness 0.15)
				)
				(justify left bottom)
				(hide yes)
			)
		)
		(property "MPN" "GRM155R61H104KE14D"
			(at 50.8 154.94 0)
			(effects
				(font
					(size 1.27 1.27)
					(thickness 0.15)
				)
				(justify left bottom)
				(hide yes)
			)
		)
		(property "Val" "100n"
			(at 67.31 139.065 0)
			(effects
				(font
					(size 1.27 1.27)
					(thickness 0.15)
				)
				(justify left bottom)
			)
		)
		(property "License" "Apache-2.0"
			(at 50.8 160.02 0)
			(effects
				(font
					(size 1.27 1.27)
					(thickness 0.15)
				)
				(justify left bottom)
				(hide yes)
			)
		)
		(property "Author" "Antmicro"
			(at 50.8 162.56 0)
			(effects
				(font
					(size 1.27 1.27)
					(thickness 0.15)
				)
				(justify left bottom)
				(hide yes)
			)
		)
		(property "Voltage" "50V"
			(at 50.8 165.1 0)
			(effects
				(font
					(size 1.27 1.27)
				)
				(justify left bottom)
				(hide yes)
			)
		)
		(property "Dielectric" "X5R"
			(at 50.8 167.64 0)
			(effects
				(font
					(size 1.27 1.27)
				)
				(justify left bottom)
				(hide yes)
			)
		)
		(pin "1"
		)
		(pin "2"
		)
		(instances
			(project "jetson-orin-baseboard"
				(path ""
					(reference "C135")
					(unit 1)
				)
			)
		)
	)
)
